%#################################################################
Title:        Cref Error Report
Design:       t6g
Date:         Mar 2 17:28:10 2023
%#################################################################



Warnings in Page : @t6g_mb_lib.t6g(sch_1):Page10
Signal M_A_CPU0_ALERT_R_N at (A 4) is labeled only once in the design.
Signal TP_M_A_CPU0_SA_TEST40 at (A 4) is labeled only once in the design.
Signal TP_M_A_CPU0_SA_TEST39A at (A 4) is labeled only once in the design.

Warnings in Page : @t6g_mb_lib.t6g(sch_1):Page11
Signal TP_M_B_CPU0_SA_TEST39B at (A 4) is labeled only once in the design.
Signal M_B_CPU0_ALERT_R_N at (A 4) is labeled only once in the design.

Warnings in Page : @t6g_mb_lib.t6g(sch_1):Page12
Signal TP_M_C_CPU0_SA_TEST39C at (A 4) is labeled only once in the design.
Signal M_C_CPU0_ALERT_R_N at (A 4) is labeled only once in the design.

Warnings in Page : @t6g_mb_lib.t6g(sch_1):Page13
Signal TP_M_D_CPU0_SA_TEST39D at (A 4) is labeled only once in the design.
Signal M_D_CPU0_ALERT_R_N at (A 4) is labeled only once in the design.

Warnings in Page : @t6g_mb_lib.t6g(sch_1):Page14
Signal TP_M_E_CPU0_SA_TEST39E at (A 4) is labeled only once in the design.
Signal M_E_CPU0_ALERT_R_N at (A 4) is labeled only once in the design.

Warnings in Page : @t6g_mb_lib.t6g(sch_1):Page15
Signal TP_M_F_CPU0_SA_TEST39F at (A 4) is labeled only once in the design.
Signal M_F_CPU0_ALERT_R_N at (A 4) is labeled only once in the design.

Warnings in Page : @t6g_mb_lib.t6g(sch_1):Page16
Signal TP_M_G_CPU0_SA_TEST39G at (A 4) is labeled only once in the design.
Signal M_G_CPU0_ALERT_R_N at (A 4) is labeled only once in the design.

Warnings in Page : @t6g_mb_lib.t6g(sch_1):Page17
Signal TP_M_H_CPU0_SA_TEST39H at (A 4) is labeled only once in the design.
Signal M_H_CPU0_ALERT_R_N at (A 4) is labeled only once in the design.

Warnings in Page : @t6g_mb_lib.t6g(sch_1):Page18
Signal TP_M_I_CPU0_SA_TEST39I at (A 4) is labeled only once in the design.
Signal M_I_CPU0_ALERT_R_N at (A 4) is labeled only once in the design.

Warnings in Page : @t6g_mb_lib.t6g(sch_1):Page19
Signal TP_M_J_CPU0_SA_TEST39J at (A 4) is labeled only once in the design.
Signal M_J_CPU0_ALERT_R_N at (A 4) is labeled only once in the design.

Warnings in Page : @t6g_mb_lib.t6g(sch_1):Page20
Signal TP_M_K_CPU0_SA_TEST39K at (A 4) is labeled only once in the design.
Signal M_K_CPU0_ALERT_R_N at (A 4) is labeled only once in the design.

Warnings in Page : @t6g_mb_lib.t6g(sch_1):Page21
Signal TP_M_L_CPU0_SA_TEST39L at (A 4) is labeled only once in the design.
Signal M_L_CPU0_ALERT_R_N at (A 4) is labeled only once in the design.

Warnings in Page : @t6g_mb_lib.t6g(sch_1):Page26
Signal P2E_CPU0_P5_TX_DN at (B 2) is labeled only once in the design.
Signal P2E_CPU0_P5_TX_DP at (B 2) is labeled only once in the design.

Warnings in Page : @t6g_mb_lib.t6g(sch_1):Page27
Signal CPU0_XTRIG_R1_L4 at (B 1) is labeled only once in the design.
Signal TP_CPU0_TEST6_CCD2 at (B 2) is labeled only once in the design.
Signal TP_CPU0_TEST6_CCD3 at (B 2) is labeled only once in the design.
Signal TP_CPU0_TEST4_CCD7 at (B 2) is labeled only once in the design.
Signal TP_CPU0_TEST5_CCD8 at (A 2) is labeled only once in the design.
Signal UART_CPU0_UART0_R_TX at (A 2) is labeled only once in the design.
Signal TP_CPU0_UART0_INTR at (A 2) is labeled only once in the design.
Signal TP_UART_CPU0_UART0_RTS_N at (A 2) is labeled only once in the design.
Signal TP_CPU0_TEST6_IOD at (B 2) is labeled only once in the design.
Signal SVID_PVDDCR_CPU0_P0_SVC at (B 3) is labeled only once in the design.
Signal SVID_PVDDCR_CPU1_P0_SVD at (B 3) is labeled only once in the design.
Signal FM_BIOS_USB_RECOVERY_R at (A 2) is labeled only once in the design.
Signal CPU0_XTRIG_R2_L6 at (B 2) is labeled only once in the design.
Signal CPU0_XTRIG_R2_L7 at (B 2) is labeled only once in the design.
Signal CPU0_XTRIG_R2_L5 at (B 2) is labeled only once in the design.
Signal CPU0_XTRIG_R2_L4 at (B 2) is labeled only once in the design.
Signal JTAG_CPU0_R_TDO at (B 3) is labeled only once in the design.
Signal TP_CPU0_TEST5_CCD5 at (A 2) is labeled only once in the design.
Signal TP_CPU0_TEST6_CCD0 at (B 2) is labeled only once in the design.
Signal TP_CPU0_TEST47_IOD0 at (B 4) is labeled only once in the design.
Signal TP_CPU0_TEST47_IOD1 at (B 4) is labeled only once in the design.
Signal TP_CPU0_TEST5_IOD at (A 2) is labeled only once in the design.
Signal TP_CPU0_TEST6_CCD1 at (B 2) is labeled only once in the design.
Signal TP_CPU0_TEST47_CCD0 at (B 4) is labeled only once in the design.
Signal TP_CPU0_TEST47_CCD1 at (B 4) is labeled only once in the design.
Signal NC_CPU0_AZ_SYNC at (B 2) is labeled only once in the design.
Signal NC_CPU0_AZ_SDOUT at (B 2) is labeled only once in the design.
Signal NC_CPU0_AZ_SDIN2 at (B 2) is labeled only once in the design.
Signal NC_CPU0_AZ_SDIN1 at (B 2) is labeled only once in the design.
Signal NC_CPU0_AZ_SDIN0 at (B 2) is labeled only once in the design.
Signal NC_CPU0_AZ_RST_N at (B 2) is labeled only once in the design.
Signal TP_CPU0_TEST50_IOD at (B 4) is labeled only once in the design.
Signal TP_CPU0_TEST4_IOD at (A 2) is labeled only once in the design.
Signal TP_CPU0_TEST5_CCD9 at (A 2) is labeled only once in the design.
Signal TP_CPU0_TEST5_CCD10 at (A 2) is labeled only once in the design.
Signal TP_CPU0_TEST5_CCD11 at (A 2) is labeled only once in the design.
Signal TP_CPU0_TEST6_X3D4 at (B 2) is labeled only once in the design.
Signal TP_CPU0_TEST5_CCD0 at (A 2) is labeled only once in the design.
Signal TP_CPU0_TEST6_X3D5 at (B 2) is labeled only once in the design.
Signal TP_CPU0_TEST5_CCD1 at (A 2) is labeled only once in the design.
Signal TP_CPU0_TEST4_CCD0 at (B 2) is labeled only once in the design.
Signal TP_CPU0_TEST4_CCD1 at (B 2) is labeled only once in the design.
Signal TP_CPU0_TEST5_CCD3 at (A 2) is labeled only once in the design.
Signal TP_CPU0_TEST4_CCD2 at (B 2) is labeled only once in the design.
Signal TP_CPU0_TEST5_CCD4 at (A 2) is labeled only once in the design.
Signal TP_CPU0_TEST4_CCD3 at (B 2) is labeled only once in the design.
Signal TP_CPU0_TEST4_CCD4 at (B 2) is labeled only once in the design.
Signal TP_CPU0_TEST5_CCD6 at (A 2) is labeled only once in the design.
Signal TP_CPU0_TEST4_CCD5 at (B 2) is labeled only once in the design.
Signal TP_CPU0_TEST5_CCD7 at (A 2) is labeled only once in the design.
Signal TP_CPU0_TEST4_CCD6 at (B 2) is labeled only once in the design.
Signal TP_CPU0_TEST4_CCD8 at (B 2) is labeled only once in the design.
Signal TP_CPU0_TEST4_CCD10 at (B 2) is labeled only once in the design.
Signal TP_CPU0_TEST4_CCD9 at (B 2) is labeled only once in the design.
Signal TP_CPU0_TEST4_CCD11 at (B 2) is labeled only once in the design.
Signal TP_CPU0_TEST6_X3D0 at (B 2) is labeled only once in the design.
Signal TP_CPU0_TEST6_X3D1 at (B 2) is labeled only once in the design.
Signal TP_CPU0_TEST6_X3D2 at (B 2) is labeled only once in the design.
Signal TP_CPU0_TEST6_X3D3 at (B 2) is labeled only once in the design.
Signal TP_CPU0_TEST5_CCD2 at (A 2) is labeled only once in the design.
Signal NC_CPU0_AZ_BITCLK at (B 2) is labeled only once in the design.
Signal CPU0_XTRIG_R1_L5 at (B 1) is labeled only once in the design.
Signal CPU0_XTRIG_R1_L6 at (B 1) is labeled only once in the design.
Signal CPU0_XTRIG_R1_L7 at (B 1) is labeled only once in the design.
Signal TP_CPU0_TEST41_IDO at (A 2) is labeled only once in the design.
Signal UART_CPU0_SCM_UART1_R_TX at (A 2) is labeled only once in the design.
Signal TP_VSENSE_PVDD33_S5_P0 at (A 4) is labeled only once in the design.
Signal SVID_PVDDCR_CPU1_P0_SVC at (B 3) is labeled only once in the design.
Signal SVID_PVDDCR_CPU0_P0_SVD at (B 3) is labeled only once in the design.
Signal TP_CPU0_TEST47_CCD2 at (B 4) is labeled only once in the design.
Signal TP_CPU0_TEST47_CCD3 at (B 4) is labeled only once in the design.
Signal CPU0_RTC_LDO_SELECT at (A 3) is labeled only once in the design.

Warnings in Page : @t6g_mb_lib.t6g(sch_1):Page28
Signal CLK_100M_CPU0_CLK04_R_DN at (B 2) is labeled only once in the design.
Signal FM_BIOS_POST_CMPLT_R_N at (B 4) is labeled only once in the design.
Signal CLK_100M_CPU0_CLK03_R_DN at (B 2) is labeled only once in the design.
Signal CLK_100M_CPU0_CLK03_R_DP at (B 2) is labeled only once in the design.
Signal CLK_100M_CPU0_CLK01_R_DP at (B 2) is labeled only once in the design.
Signal CLK_100M_CPU0_CLK02_R_DP at (B 2) is labeled only once in the design.
Signal CLK_100M_CPU0_CLK02_R_DN at (B 2) is labeled only once in the design.
Signal  SMB_CPU0_3_SDA at (B 4) is labeled only once in the design.
Signal  SMB_CPU0_3_SCL at (B 4) is labeled only once in the design.
Signal  SMB_CPU0_2_SDA at (B 4) is labeled only once in the design.
Signal SMB_CPU0_2_R_SDA at (B 4) is labeled only once in the design.
Signal  SMB_CPU0_2_SCL at (B 4) is labeled only once in the design.
Signal FM_PASSWORD_CLEAR_R_N at (B 4) is labeled only once in the design.
Signal SMB_CPU0_4_R_SCL at (B 4) is labeled only once in the design.
Signal SMB_CPU0_4_R_SDA at (B 4) is labeled only once in the design.
Signal SMB_CPU_5_R_SDA at (B 4) is labeled only once in the design.
Signal    BOOT_RDY_R_H at (B 4) is labeled only once in the design.
Signal CLK_100M_REF_OUT_DP at (B 2) is labeled only once in the design.
Signal CLK_100M_REF_OUT_DN at (B 2) is labeled only once in the design.
Signal CLK_100M_CPU0_CLK01_R_DN at (B 2) is labeled only once in the design.
Signal SMB_CPU0_2_R_SCL at (B 4) is labeled only once in the design.
Signal XTAL_CPU0_X48M_X2_R at (A 3) is labeled only once in the design.
Signal CLK_100M_CPU0_CLK12_R_DP at (B 2) is labeled only once in the design.
Signal CLK_100M_CPU0_CLK12_R_DN at (B 2) is labeled only once in the design.
Signal CLK_100M_CPU0_CLK13_R_DP at (B 2) is labeled only once in the design.
Signal CLK_100M_CPU0_CLK13_R_DN at (B 2) is labeled only once in the design.
Signal CLK_100M_CPU0_CLK04_R_DP at (B 2) is labeled only once in the design.
Signal CLK_100M_CPU0_CLK05_R_DP at (B 2) is labeled only once in the design.
Signal CLK_100M_CPU0_CLK05_R_DN at (B 2) is labeled only once in the design.
Signal CLK_100M_CPU0_CLK11_R_DP at (B 2) is labeled only once in the design.
Signal CLK_100M_CPU0_CLK11_R_DN at (B 2) is labeled only once in the design.
Signal SMB_CPU0_3_R_SDA at (B 4) is labeled only once in the design.
Signal SMB_CPU0_3_R_SCL at (B 4) is labeled only once in the design.
Signal SMB_CPU_5_R_SCL at (B 4) is labeled only once in the design.
Signal   CPU0_SLP_S3_N at (B 4) has too little display space.
Signal   CPU0_SLP_S5_N at (B 4) has too little display space.

Warnings in Page : @t6g_mb_lib.t6g(sch_1):Page29
Signal ESPI_CPU0_R_CS1_N at (B 4) is labeled only once in the design.
Signal CPU0_ESPI_CS0_N at (B 4) is labeled only once in the design.
Signal  SPI_CPU0_R_CLK at (B 4) is labeled only once in the design.
Signal NC_CPU0_SPI_CS2_N at (B 4) is labeled only once in the design.
Signal SPI_CPU0_R_CS1_N at (B 4) is labeled only once in the design.
Signal   SPI_CPU0_R_D2 at (B 4) is labeled only once in the design.
Signal   SPI_CPU0_R_D1 at (B 4) is labeled only once in the design.
Signal   SPI_CPU0_R_D0 at (B 4) is labeled only once in the design.
Signal   SPI_CPU0_R_D3 at (B 4) is labeled only once in the design.
Signal SPI_CPU0_R_TPM_CS_N at (B 4) is labeled only once in the design.
Signal SPI_CPU0_R_CS0_N at (B 4) is labeled only once in the design.
Signal RST_ESPI_CPU0_R_RSTOUT_N at (B 4) is labeled only once in the design.
Signal  ESPI_CPU0_R_D0 at (B 4) is labeled only once in the design.
Signal SCM_USB_OC_BU_R_N at (A 2) is labeled only once in the design.
Signal  ESPI_CPU0_R_D1 at (B 4) is labeled only once in the design.
Signal  ESPI_CPU0_R_D3 at (B 4) is labeled only once in the design.
Signal  ESPI_CPU0_R_D2 at (B 4) is labeled only once in the design.
Signal ESPI_CPU0_R_ALERT_N at (B 4) is labeled only once in the design.
Signal CPU0_ESPI0_ALERT_N at (B 4) is labeled only once in the design.
Signal CLK_ESPI_CPU0_R_CLK1 at (B 4) is labeled only once in the design.

Warnings in Page : @t6g_mb_lib.t6g(sch_1):Page34
Signal FM_BIOS_POST_CMPLT_BUF_R1_N at (B 4) is labeled only once in the design.
Signal       TP_U27_EN at (B 4) is labeled only once in the design.

Warnings in Page : @t6g_mb_lib.t6g(sch_1):Page37
Signal TP_M_A_CPU1_SA_TEST39A at (A 4) is labeled only once in the design.
Signal TP_M_A_CPU1_SA_TEST40 at (A 4) is labeled only once in the design.
Signal M_A_CPU1_ALERT_R_N at (A 4) is labeled only once in the design.

Warnings in Page : @t6g_mb_lib.t6g(sch_1):Page38
Signal TP_M_B_CPU1_SA_TEST39B at (A 4) is labeled only once in the design.
Signal M_B_CPU1_ALERT_R_N at (A 4) is labeled only once in the design.

Warnings in Page : @t6g_mb_lib.t6g(sch_1):Page39
Signal TP_M_C_CPU1_SA_TEST39C at (A 4) is labeled only once in the design.
Signal M_C_CPU1_ALERT_R_N at (A 4) is labeled only once in the design.

Warnings in Page : @t6g_mb_lib.t6g(sch_1):Page40
Signal TP_M_D_CPU1_SA_TEST39D at (A 4) is labeled only once in the design.
Signal M_D_CPU1_ALERT_R_N at (A 4) is labeled only once in the design.

Warnings in Page : @t6g_mb_lib.t6g(sch_1):Page41
Signal TP_M_E_CPU1_SA_TEST39E at (A 4) is labeled only once in the design.
Signal M_E_CPU1_ALERT_R_N at (A 4) is labeled only once in the design.

Warnings in Page : @t6g_mb_lib.t6g(sch_1):Page42
Signal TP_M_F_CPU1_SA_TEST39F at (A 4) is labeled only once in the design.
Signal M_F_CPU1_ALERT_R_N at (A 4) is labeled only once in the design.

Warnings in Page : @t6g_mb_lib.t6g(sch_1):Page43
Signal TP_M_G_CPU1_SA_TEST39G at (A 4) is labeled only once in the design.
Signal M_G_CPU1_ALERT_R_N at (A 4) is labeled only once in the design.

Warnings in Page : @t6g_mb_lib.t6g(sch_1):Page44
Signal TP_M_H_CPU1_SA_TEST39H at (A 4) is labeled only once in the design.
Signal M_H_CPU1_ALERT_R_N at (A 4) is labeled only once in the design.

Warnings in Page : @t6g_mb_lib.t6g(sch_1):Page45
Signal TP_M_I_CPU1_SA_TEST39I at (A 4) is labeled only once in the design.
Signal M_I_CPU1_ALERT_R_N at (A 4) is labeled only once in the design.

Warnings in Page : @t6g_mb_lib.t6g(sch_1):Page46
Signal TP_M_J_CPU1_SA_TEST39J at (A 4) is labeled only once in the design.
Signal M_J_CPU1_ALERT_R_N at (A 4) is labeled only once in the design.

Warnings in Page : @t6g_mb_lib.t6g(sch_1):Page47
Signal TP_M_K_CPU1_SA_TEST39K at (A 4) is labeled only once in the design.
Signal M_K_CPU1_ALERT_R_N at (A 4) is labeled only once in the design.

Warnings in Page : @t6g_mb_lib.t6g(sch_1):Page48
Signal TP_M_L_CPU1_SA_TEST39L at (A 4) is labeled only once in the design.
Signal M_L_CPU1_ALERT_R_N at (A 4) is labeled only once in the design.

Warnings in Page : @t6g_mb_lib.t6g(sch_1):Page53
Signal P3E_CPU1_P5_TX_DP<1> at (B 2) is labeled only once in the design.
Signal P3E_CPU1_P5_TX_DN<1> at (B 2) is labeled only once in the design.
Signal P3E_CPU1_P5_TX_DN<0> at (B 2) is labeled only once in the design.
Signal P3E_CPU1_P5_TX_DP<0> at (B 2) is labeled only once in the design.

Warnings in Page : @t6g_mb_lib.t6g(sch_1):Page54
Signal TP_CPU1_TEST5_CCD2 at (B 2) is labeled only once in the design.
Signal CPU1_XTRIG_R1_L4 at (B 1) is labeled only once in the design.
Signal CPU1_XTRIG_R1_L5 at (B 1) is labeled only once in the design.
Signal CPU1_XTRIG_R1_L6 at (B 1) is labeled only once in the design.
Signal CPU1_XTRIG_R1_L7 at (B 1) is labeled only once in the design.
Signal CPU1_XTRIG_R2_L6 at (B 2) is labeled only once in the design.
Signal CPU1_XTRIG_R2_L7 at (B 2) is labeled only once in the design.
Signal CPU1_XTRIG_R2_L4 at (B 2) is labeled only once in the design.
Signal CPU1_XTRIG_R2_L5 at (B 2) is labeled only once in the design.
Signal SVID_PVDDCR_CPU1_P1_SVC at (B 4) is labeled only once in the design.
Signal SVID_PVDDCR_CPU1_P1_SVD at (B 4) is labeled only once in the design.
Signal SVID_PVDDCR_CPU0_P1_SVC at (B 4) is labeled only once in the design.
Signal SVID_PVDDCR_CPU0_P1_SVD at (B 4) is labeled only once in the design.
Signal JTAG_CPU1_R_TDO at (B 3) is labeled only once in the design.
Signal TP_CPU1_TEST50_IOD at (B 4) is labeled only once in the design.
Signal TP_VSENSE_PVDD33_S5_P1 at (A 4) is labeled only once in the design.
Signal TP_CPU1_TEST47_CCD0 at (B 4) is labeled only once in the design.
Signal TP_CPU1_TEST47_CCD1 at (B 4) is labeled only once in the design.
Signal TP_CPU1_TEST47_CCD2 at (B 4) is labeled only once in the design.
Signal TP_CPU1_TEST47_IOD0 at (B 4) is labeled only once in the design.
Signal TP_CPU1_TEST47_IOD1 at (B 4) is labeled only once in the design.
Signal TP_CPU1_TEST47_CCD3 at (B 4) is labeled only once in the design.
Signal TP_CPU1_UART0_INTR at (A 2) is labeled only once in the design.
Signal TP_CPU1_TEST5_IOD at (A 2) is labeled only once in the design.
Signal TP_CPU1_TEST41_IOD at (A 2) is labeled only once in the design.
Signal TP_CPU1_UART0_RX at (A 2) is labeled only once in the design.
Signal TP_CPU1_UART0_RTS_N at (A 2) is labeled only once in the design.
Signal TP_CPU1_UART0_TX at (A 2) is labeled only once in the design.
Signal TP_CPU1_UART0_CTS_N at (A 2) is labeled only once in the design.
Signal TP_CPU1_UART1_RX at (A 2) is labeled only once in the design.
Signal TP_CPU1_TEST5_CCD0 at (B 2) is labeled only once in the design.
Signal TP_CPU1_TEST5_CCD1 at (B 2) is labeled only once in the design.
Signal TP_CPU1_TEST5_CCD3 at (B 2) is labeled only once in the design.
Signal TP_CPU1_TEST4_IOD at (A 2) is labeled only once in the design.
Signal TP_CPU1_TEST5_CCD4 at (B 2) is labeled only once in the design.
Signal TP_CPU1_TEST5_CCD5 at (A 2) is labeled only once in the design.
Signal TP_CPU1_TEST5_CCD6 at (A 2) is labeled only once in the design.
Signal TP_CPU1_TEST5_CCD7 at (A 2) is labeled only once in the design.
Signal TP_CPU1_TEST5_CCD8 at (A 2) is labeled only once in the design.
Signal TP_CPU1_TEST4_CCD7 at (B 2) is labeled only once in the design.
Signal TP_CPU1_TEST5_CCD9 at (A 2) is labeled only once in the design.
Signal TP_CPU1_TEST4_CCD8 at (B 2) is labeled only once in the design.
Signal TP_CPU1_TEST4_CCD10 at (B 2) is labeled only once in the design.
Signal TP_CPU1_TEST4_CCD9 at (B 2) is labeled only once in the design.
Signal TP_CPU1_TEST5_CCD10 at (A 2) is labeled only once in the design.
Signal TP_CPU1_TEST4_CCD11 at (B 2) is labeled only once in the design.
Signal TP_CPU1_TEST5_CCD11 at (A 2) is labeled only once in the design.
Signal TP_CPU1_TEST6_X3D4 at (B 2) is labeled only once in the design.
Signal TP_CPU1_TEST6_CCD1 at (B 2) is labeled only once in the design.
Signal TP_CPU1_TEST6_X3D5 at (B 2) is labeled only once in the design.
Signal TP_CPU1_TEST4_CCD0 at (B 2) is labeled only once in the design.
Signal TP_CPU1_TEST4_CCD1 at (B 2) is labeled only once in the design.
Signal TP_CPU1_TEST4_CCD2 at (B 2) is labeled only once in the design.
Signal TP_CPU1_TEST4_CCD3 at (B 2) is labeled only once in the design.
Signal TP_CPU1_TEST6_IOD at (B 2) is labeled only once in the design.
Signal TP_CPU1_TEST4_CCD4 at (B 2) is labeled only once in the design.
Signal TP_CPU1_TEST4_CCD5 at (B 2) is labeled only once in the design.
Signal TP_CPU1_TEST4_CCD6 at (B 2) is labeled only once in the design.
Signal TP_CPU1_TEST6_X3D0 at (B 2) is labeled only once in the design.
Signal TP_CPU1_TEST6_X3D1 at (B 2) is labeled only once in the design.
Signal TP_CPU1_TEST6_X3D2 at (B 2) is labeled only once in the design.
Signal TP_CPU1_TEST6_X3D3 at (B 2) is labeled only once in the design.
Signal NC_CPU1_AZ_BITCLK at (B 2) is labeled only once in the design.
Signal NC_CPU1_AZ_SDIN2 at (B 2) is labeled only once in the design.
Signal NC_CPU1_AZ_SDOUT at (B 2) is labeled only once in the design.
Signal NC_CPU1_AZ_SDIN1 at (B 2) is labeled only once in the design.
Signal NC_CPU1_AZ_RST_N at (B 2) is labeled only once in the design.
Signal NC_CPU1_AZ_SDIN0 at (B 2) is labeled only once in the design.
Signal NC_CPU1_AZ_SYNC at (B 2) is labeled only once in the design.
Signal TP_CPU1_TEST6_CCD0 at (B 2) is labeled only once in the design.
Signal TP_CPU1_TEST6_CCD2 at (B 2) is labeled only once in the design.
Signal TP_CPU1_TEST6_CCD3 at (B 2) is labeled only once in the design.

Warnings in Page : @t6g_mb_lib.t6g(sch_1):Page55
Signal CLK_100M_CPU1_CLK04_R_DP at (B 2) is labeled only once in the design.
Signal CLK_100M_CPU1_CLK05_R_DN at (B 2) is labeled only once in the design.
Signal CLK_100M_CPU1_CLK02_R_DP at (B 2) is labeled only once in the design.
Signal CLK_100M_CPU1_CLK02_R_DN at (B 2) is labeled only once in the design.
Signal CLK_100M_CPU1_CLK03_R_DP at (B 2) is labeled only once in the design.
Signal CLK_100M_CPU1_CLK03_R_DN at (B 2) is labeled only once in the design.
Signal XTAL_CPU1_X48M_X2_R at (A 3) is labeled only once in the design.
Signal NC_CPU1_PWR_BTN_N at (B 4) is labeled only once in the design.
Signal CLK_100M_CPU1_CLK04_R_DN at (B 2) is labeled only once in the design.
Signal CLK_100M_CPU1_CLK01_R_DN at (B 2) is labeled only once in the design.
Signal CLK_100M_CPU1_CLK01_R_DP at (B 2) is labeled only once in the design.
Signal INT_CPU1_HP_UBM_N at (B 4) is labeled only once in the design.
Signal CPU1_SPD_HOST_CTRL_R_N at (B 4) is labeled only once in the design.
Signal XTAL_CPU1_R_X32K_X1 at (A 2) is labeled only once in the design.
Signal XTAL_CPU1_R_X32K_X2 at (A 2) is labeled only once in the design.
Signal CLK_100M_CPU1_CLK05_R_DP at (B 2) is labeled only once in the design.
Signal CLK_100M_CPU1_CLK11_R_DP at (B 2) is labeled only once in the design.
Signal CLK_100M_CPU1_CLK11_R_DN at (B 2) is labeled only once in the design.
Signal CLK_100M_CPU1_CLK12_R_DP at (B 2) is labeled only once in the design.
Signal CLK_100M_CPU1_CLK12_R_DN at (B 2) is labeled only once in the design.
Signal CLK_100M_CPU1_CLK13_R_DP at (B 2) is labeled only once in the design.
Signal CLK_100M_CPU1_CLK13_R_DN at (B 2) is labeled only once in the design.
Signal TP_SLOT2_BUF_SKU_ID0 at (B 4) is labeled only once in the design.
Signal TP_SLOT2_BUF_SKU_ID1 at (B 4) is labeled only once in the design.
Signal   CPU1_SLP_S5_N at (B 4) has too little display space.
Signal   CPU1_SLP_S3_N at (B 4) has too little display space.

Warnings in Page : @t6g_mb_lib.t6g(sch_1):Page56
Signal NC_CPU1_USB3_USB11_RXP at (B 2) is labeled only once in the design.
Signal NC_CPU1_USB3_USB11_RXN at (B 2) is labeled only once in the design.
Signal NC_CPU1_USB2_USB11_DP at (B 2) is labeled only once in the design.
Signal NC_CPU1_USB2_USB11_DN at (B 2) is labeled only once in the design.
Signal NC_CPU1_USB3_USB10_TXP at (B 2) is labeled only once in the design.
Signal NC_CPU1_USB3_USB10_TXN at (B 2) is labeled only once in the design.
Signal NC_CPU1_USB3_USB10_RXP at (B 2) is labeled only once in the design.
Signal NC_CPU1_USB3_USB10_RXN at (B 2) is labeled only once in the design.
Signal NC_CPU1_USB2_USB10_DP at (B 2) is labeled only once in the design.
Signal NC_CPU1_USB2_USB10_DN at (B 2) is labeled only once in the design.
Signal NC_CPU1_USB3_USB01_TXP at (B 2) is labeled only once in the design.
Signal NC_CPU1_USB3_USB01_TXN at (B 2) is labeled only once in the design.
Signal NC_CPU1_USB3_USB01_RXP at (B 2) is labeled only once in the design.
Signal NC_CPU1_USB3_USB01_RXN at (B 2) is labeled only once in the design.
Signal NC_CPU1_USB2_USB01_DP at (B 2) is labeled only once in the design.
Signal NC_CPU1_USB2_USB01_DN at (B 2) is labeled only once in the design.
Signal NC_CPU1_USB3_USB00_TXN at (B 2) is labeled only once in the design.
Signal NC_CPU1_USB3_USB00_TXP at (B 2) is labeled only once in the design.
Signal NC_CPU1_USB3_USB00_RXP at (B 2) is labeled only once in the design.
Signal NC_CPU1_USB3_USB00_RXN at (B 2) is labeled only once in the design.
Signal NC_CPU1_USB2_USB00_DP at (B 2) is labeled only once in the design.
Signal NC_CPU1_USB2_USB00_DN at (B 2) is labeled only once in the design.
Signal NC_CPU1_USB01_OC_N at (B 2) is labeled only once in the design.
Signal NC_CPU1_USB00_OC_N at (B 2) is labeled only once in the design.
Signal NC_CPU1_USB11_OC_N at (B 2) is labeled only once in the design.
Signal NC_CPU1_USB10_OC_N at (B 2) is labeled only once in the design.
Signal NC_CPU1_USB3_USB11_TXP at (B 2) is labeled only once in the design.
Signal NC_CPU1_USB3_USB11_TXN at (B 2) is labeled only once in the design.
Signal  SPI_CPU1_R_CLK at (B 4) is labeled only once in the design.

Warnings in Page : @t6g_mb_lib.t6g(sch_1):Page57
Signal CPU1_VDDBT_RTC_G at (A 1) is labeled only once in the design.

Warnings in Page : @t6g_mb_lib.t6g(sch_1):Page77
Signal SPI_CPU0_LVC3_R_TPM_CS_N at (B 3) is labeled only once in the design.
Signal  SPI_CPU0_R1_D0 at (A 4) is labeled only once in the design.
Signal  SPI_CPU0_R1_D2 at (A 4) is labeled only once in the design.
Signal  SPI_CPU0_R1_D3 at (A 4) is labeled only once in the design.
Signal  SPI_CPU0_R1_D1 at (A 4) is labeled only once in the design.
Signal SPI_CPU0_LVC3_D3 at (A 3) is labeled only once in the design.
Signal SPI_CPU0_LVC3_D2 at (A 3) is labeled only once in the design.
Signal SPI_CPU0_LVC3_D0 at (A 3) is labeled only once in the design.
Signal SPI_CPU0_LVC3_D1 at (A 3) is labeled only once in the design.
Signal SPI_CPU0_LVC3_CLK at (B 3) is labeled only once in the design.
Signal SPI_CPU0_LVC3_CS1_N at (B 3) is labeled only once in the design.
Signal SPI_CPU0_LVC3_CS0_N at (B 3) is labeled only once in the design.

Warnings in Page : @t6g_mb_lib.t6g(sch_1):Page80
Signal E1S_0_PERST1_CLKREQ_R_N at (B 4) is labeled only once in the design.
Signal P12V_OCP_SFF_EN at (B 4) is labeled only once in the design.
Signal P3V3_OCP_SFF_EN at (B 4) is labeled only once in the design.
Signal IRQ_HSC_FAULT_BUF_R_N at (B 4) is labeled only once in the design.
Signal      UV_ALERT_N at (B 4) is labeled only once in the design.
Signal      OC_ALERT_N at (B 4) is labeled only once in the design.
Signal SMB_CPU0_4_XLTR_R_SCL at (B 4) is labeled only once in the design.
Signal FM_SYS_THROTTLE_R_N at (B 4) is labeled only once in the design.
Signal SMB_CPU0_4_XLTR_R_SDA at (B 4) is labeled only once in the design.
Signal SGPIO_SCM_DI_R<1> at (B 4) is labeled only once in the design.
Signal SMB_1_PLD_3V3AUX_SCL_R2 at (B 2) is labeled only once in the design.
Signal SMB_2_PLD_3V3AUX_SDA_R2 at (B 2) is labeled only once in the design.
Signal GPU_3V3IO_RSVD3_FFU_ISO_R at (B 2) is labeled only once in the design.
Signal HP_LVC3_OCP_V3_2_P12V_PWRGD_R at (B 2) is labeled only once in the design.
Signal JTAG_SCM_TRST_R_N at (B 4) is labeled only once in the design.
Signal FM_I3C_CPU1_MUX0_OE_R_N at (B 4) is labeled only once in the design.
Signal VIRTUAL_RESEAT_FPGA_R_N at (A 3) is labeled only once in the design.
Signal FM_I3C_CPU0_MUX0_R_SEL at (B 4) is labeled only once in the design.
Signal FM_I3C_CPU1_MUX1_R_SEL at (B 4) is labeled only once in the design.
Signal SGPIO_SCM_INTR_R_N at (B 4) is labeled only once in the design.
Signal SGPIO_SCM_DI_R<0> at (B 4) is labeled only once in the design.
Signal SCM_JTAG_MUX_R_S0 at (B 4) is labeled only once in the design.
Signal FM_I3C_CPU0_MUX1_OE_R_N at (B 4) is labeled only once in the design.
Signal SCM_JTAG_MUX_R_S1 at (B 4) is labeled only once in the design.
Signal FM_I3C_CPU0_MUX1_R_SEL at (B 4) is labeled only once in the design.
Signal FM_I3C_CPU1_MUX1_OE_R_N at (B 4) is labeled only once in the design.
Signal FM_I3C_CPU1_MUX0_R_SEL at (B 4) is labeled only once in the design.
Signal FM_I3C_CPU0_MUX0_OE_R_N at (B 4) is labeled only once in the design.
Signal FM_UV_ADR_TRIGGER_R_N at (B 4) is labeled only once in the design.
Signal SMB_2_PLD_3V3AUX_SCL_R2 at (B 2) is labeled only once in the design.
Signal   SCM_SYS_PWROK at (B 2) is labeled only once in the design.
Signal       PWRGD_P5V at (B 2) is labeled only once in the design.
Signal PRSNT_OCP_V3_2_N at (B 2) is labeled only once in the design.
Signal RST_SRST_PLD_BMC_R_N at (B 2) is labeled only once in the design.
Signal P1V8_RETIMER_CPU0_R_EN at (B 2) is labeled only once in the design.
Signal PRSNT_CABLE_GPU_B3_ISO_R_N at (B 2) is labeled only once in the design.
Signal SMB_1_PLD_3V3AUX_SDA_R2 at (B 2) is labeled only once in the design.
Signal CLK_GEN2_GPU_FPGA_OE_R_N at (B 2) is labeled only once in the design.
Signal FM_OCP_V3_2_AUX_PWR_EN at (B 2) is labeled only once in the design.
Signal P1V8_RETIMER_CPU1_R_EN at (B 2) is labeled only once in the design.
Signal CLK_GEN2_BMC_RC_OE_R_N at (B 2) is labeled only once in the design.

Warnings in Page : @t6g_mb_lib.t6g(sch_1):Page81
Signal PWRGD_P3V3_AUX_R at (A 4) is labeled only once in the design.
Signal FM_CPU0_SYS_RESET_N at (B 4) is labeled only once in the design.
Signal PRSNT_OCP_SFF_N at (B 4) is labeled only once in the design.
Signal FM_PWRGD_PVDDIO_P0 at (B 4) is labeled only once in the design.
Signal RST_RT_CPU0_P2_RESET_R2_N at (B 3) is labeled only once in the design.
Signal FM_CPU1_NMI_SYNC_FLOOD_N at (B 3) is labeled only once in the design.
Signal TP_PWRGD_P12V_FAN_DR_R at (B 2) is labeled only once in the design.
Signal FM_CPU0_HDT_CONN_TESTEN at (B 3) is labeled only once in the design.
Signal RST_RT_CPU0_P2_PERST_R2_N at (B 3) is labeled only once in the design.
Signal FM_ESPI_CPU0_ALERT_SEL at (B 3) is labeled only once in the design.
Signal FM_HDT_HDR_RESET_N at (B 3) is labeled only once in the design.
Signal FM_BIOS_POST_CMPLT_BUF_R_N at (B 3) is labeled only once in the design.
Signal RST_RT_CPU0_P3_PERST_R2_N at (B 3) is labeled only once in the design.
Signal FM_CPU1_FORCE_SELFREFRESH at (B 3) is labeled only once in the design.
Signal     BMC_MONITER at (A 4) is labeled only once in the design.
Signal FM_PVDD18_S5_P0_EN at (A 4) is labeled only once in the design.
Signal GPU_WP_HW_CTRL_R_N at (A 2) is labeled only once in the design.
Signal GPU_3V3IO_RSVD1_ISO_R at (B 2) is labeled only once in the design.
Signal GPU_3V3IO_RSVD3_ISO_R at (B 2) is labeled only once in the design.
Signal RST_PERST_E1S_0_R_N at (B 2) is labeled only once in the design.
Signal RST_SMB_RT_R2_N at (B 3) is labeled only once in the design.
Signal FM_FORCE_ALL_PWRON_R at (B 3) is labeled only once in the design.
Signal FM_CPU0_FORCE_SELFREFRESH at (B 3) is labeled only once in the design.
Signal FM_CPU1_PWRGD_OUT at (B 3) is labeled only once in the design.
Signal FM_PLD_CPU0_PRSNT_HDT at (B 3) is labeled only once in the design.
Signal FM_SPD_CPU0_SWITCH_CTRL_R_N at (B 3) is labeled only once in the design.
Signal RST_RT_CPU0_P3_RESET_R2_N at (B 3) is labeled only once in the design.
Signal FM_ROM_SD_LS_OE at (B 3) is labeled only once in the design.
Signal FM_CPU0_PWR_BTN_N at (B 4) is labeled only once in the design.
Signal  FM_P1_PCC0_R_N at (B 4) is labeled only once in the design.
Signal FM_PWRGD_CPU1_PWROK at (B 4) is labeled only once in the design.
Signal FM_CPU0_NMI_SYNC_FLOOD_N at (B 4) is labeled only once in the design.
Signal FM_CPU1_NV_SAVE_N at (B 4) is labeled only once in the design.
Signal FM_PWRGD_CPU0_PWROK at (B 4) is labeled only once in the design.
Signal CPU0_JTAG_BUF_R_OE at (B 4) is labeled only once in the design.
Signal FM_RST_CPU1_RESETL_N at (B 4) is labeled only once in the design.
Signal FM_CPU1_SYS_RESET_N at (B 4) is labeled only once in the design.
Signal FM_CPU0_NV_SAVE_N at (B 4) is labeled only once in the design.
Signal RST_RT_CPU1_P1_PERST_R2_N at (B 4) is labeled only once in the design.
Signal RST_RT_CPU1_P1_RESET_R2_N at (B 4) is labeled only once in the design.
Signal FM_RST_CPU0_RESETL_N at (B 4) is labeled only once in the design.
Signal CLK_ESPI_CPU0_R1_CLK1 at (B 3) is labeled only once in the design.
Signal  FM_JTAG_BMC_OE at (B 2) is labeled only once in the design.
Signal ESPI_CPU0_CS1_R_N at (B 3) is labeled only once in the design.
Signal CPU1_SPD_HOST_CTRL_R1_N at (B 4) is labeled only once in the design.
Signal RST_RT_CPU0_P0_PERST_R2_N at (B 4) is labeled only once in the design.
Signal RST_RT_CPU0_P0_RESET_R2_N at (B 4) is labeled only once in the design.
Signal RST_RT_CPU0_P1_PERST_R2_N at (B 4) is labeled only once in the design.
Signal FM_HDT_HDR_PWROK at (B 3) is labeled only once in the design.
Signal ESPI_CPU0_R1_D3 at (B 3) is labeled only once in the design.
Signal ESPI_CPU0_R1_D2 at (B 3) is labeled only once in the design.
Signal ESPI_CPU0_R1_D0 at (B 3) is labeled only once in the design.
Signal ESPI_CPU0_ALERT_R_N at (B 3) is labeled only once in the design.
Signal FM_CPU1_SMERR_N at (B 3) is labeled only once in the design.
Signal  SCM_USB_OC_R_N at (B 3) is labeled only once in the design.
Signal SCM_IRQ_1V8_R_N at (B 3) is labeled only once in the design.
Signal  BMC_JTAG_SEL_R at (B 3) is labeled only once in the design.
Signal CPU1_JTAG_BUF_R_OE at (B 3) is labeled only once in the design.
Signal FM_PLD_CPU1_PRSNT_HDT at (B 3) is labeled only once in the design.
Signal ESPI_CPU0_R1_D1 at (B 3) is labeled only once in the design.
Signal BIOS_DEBUG_MODE_R at (B 3) is labeled only once in the design.
Signal RST_ESPI_CPU0_RSTOUT_R_N at (B 3) is labeled only once in the design.
Signal FM_CPU0_SMERR_N at (B 3) is labeled only once in the design.
Signal FM_SMERR_LED_R_N at (B 3) is labeled only once in the design.
Signal RST_RT_CPU1_P2_PERST_R2_N at (B 4) is labeled only once in the design.
Signal   FM_SWB_PWR_EN at (B 4) is labeled only once in the design.
Signal FM_PVDDIO_P0_EN at (B 4) is labeled only once in the design.
Signal GPU_NVS_PWR_BRAKE_R_N at (B 4) is labeled only once in the design.
Signal GPU_FPGA_READY_ISO_R at (A 2) is labeled only once in the design.
Signal  HGX_DETECT_N_R at (B 2) is labeled only once in the design.
Signal FM_SWB_PWRGD_ISO_R at (A 2) is labeled only once in the design.
Signal GPU_FPGA_BOOT_EN_R at (A 2) is labeled only once in the design.
Signal FM_CPU1_PWR_GD_IN at (B 3) is labeled only once in the design.
Signal FM_RST_PERST_SCM_R_N at (B 2) is labeled only once in the design.
Signal GPU_PRSNT_N_ISO_R at (A 2) is labeled only once in the design.
Signal BIC_MONITER_ISO_R at (A 2) is labeled only once in the design.
Signal FM_SWB_BIC_READY_ISO_R_N at (A 2) is labeled only once in the design.
Signal FM_SMB_1_ALERT_GPU_ISO_R_N at (A 2) is labeled only once in the design.
Signal RST_BMC_FROM_SWB_ISO_R_N at (A 2) is labeled only once in the design.
Signal GPU_HMC_PRSNT_ISO_R_N at (A 2) is labeled only once in the design.
Signal GPU_3V3IO_RSVD4_ISO_R at (B 2) is labeled only once in the design.
Signal RST_PERST_M2_0_R_N at (A 2) is labeled only once in the design.
Signal FM_GPU_PWRGD_ISO_R at (A 2) is labeled only once in the design.
Signal    SWB_HSC_EN_R at (B 2) is labeled only once in the design.
Signal  FM_P1_PCC1_R_N at (B 4) is labeled only once in the design.
Signal RST_CPU0_KBRST_N at (B 4) is labeled only once in the design.
Signal FM_FPGA_DEBUG_LED_CTRL at (B 4) is labeled only once in the design.
Signal TP_SLOT2_CLKREQ_0_R_N at (B 4) is labeled only once in the design.
Signal SWB_HSC_PWRGD_ISO_R at (A 2) is labeled only once in the design.
Signal GPU_FPGA_OVERT_ISO_R_N at (A 2) is labeled only once in the design.
Signal GPU_FPGA_THERM_OVERT_ISO_R_N at (A 2) is labeled only once in the design.
Signal GPU_BASE_HMC_READY_ISO_R at (A 2) is labeled only once in the design.
Signal RST_RT_CPU1_P2_RESET_R2_N at (B 4) is labeled only once in the design.
Signal  FM_P0_PCC1_R_N at (B 4) is labeled only once in the design.
Signal  FM_P0_PCC0_R_N at (B 4) is labeled only once in the design.
Signal TP_FM_CLK_BUFFER_EN_R at (B 2) is labeled only once in the design.
Signal RST_SMB_RT_ROM_R2_N at (B 3) is labeled only once in the design.
Signal RST_RT_CPU1_P3_RESET_R2_N at (B 4) is labeled only once in the design.
Signal RST_RT_CPU1_P3_PERST_R2_N at (B 4) is labeled only once in the design.
Signal RST_RT_CPU0_P1_RESET_R2_N at (B 4) is labeled only once in the design.
Signal    FM_ROM_LS_EN at (B 3) is labeled only once in the design.
Signal CPU0_SPD_HOST_CTRL_R1_N at (B 3) is labeled only once in the design.
Signal P12V_ALL_PWROK_R at (B 3) is labeled only once in the design.
Signal RST_CPU0_PERST0_R_N at (B 4) is labeled only once in the design.
Signal RST_CPU1_PERST1_R_N at (B 4) is labeled only once in the design.
Signal RST_CPU0_PERST1_R_N at (B 4) is labeled only once in the design.
Signal TP_SLOT1_CLKREQ_0_R_N at (B 4) is labeled only once in the design.
Signal RST_RT_CPU1_P0_PERST_R2_N at (B 4) is labeled only once in the design.
Signal RST_RT_CPU1_P0_RESET_R2_N at (B 4) is labeled only once in the design.
Signal PWRGD_P0V9_RETIMER_CPU0_R2 at (B 4) is labeled only once in the design.
Signal RST_CPU1_PERST0_R_N at (B 4) is labeled only once in the design.
Signal FM_CPU1_RSMRST_N at (B 4) is labeled only once in the design.
Signal FM_CPU0_RSMRST_N at (B 4) is labeled only once in the design.
Signal PWRGD_P0V9_RETIMER_CPU1_R2 at (B 4) is labeled only once in the design.
Signal PRSNT_CABLE_GPU_A1_ISO_R_N at (A 2) is labeled only once in the design.
Signal GPU_3V3IO_RSVD5_FFU_ISO_R at (A 2) is labeled only once in the design.
Signal FM_PVDD11_S3_P1_EN at (A 4) is labeled only once in the design.
Signal FM_PWRGD_PVDD11_S3_P1 at (A 4) is labeled only once in the design.
Signal PVDD18_S5_P1_R_EN at (A 4) is labeled only once in the design.
Signal   FM_UART_LS_EN at (B 4) is labeled only once in the design.
Signal PRSNT_CABLE_GPU_A2_ISO_R_N at (A 2) is labeled only once in the design.
Signal GPU_3V3IO_RSVD0_FFU_ISO_R at (B 2) is labeled only once in the design.
Signal GPU_3V3IO_RSVD1_FFU_ISO_R at (A 2) is labeled only once in the design.
Signal GPU_FPGA_EROT_FATALERR_ISO_R_N at (A 2) is labeled only once in the design.
Signal FM_SMB_2_ALERT_GPU_ISO_R_N at (A 2) is labeled only once in the design.
Signal GPU_BASE_STBY_EN_R at (A 2) is labeled only once in the design.
Signal P0V9_RETIMER_CPU1_EN_R2 at (A 2) is labeled only once in the design.
Signal PU_SPI_PLD_CS_N at (A 2) is labeled only once in the design.
Signal FM_PWRGD_PVDD11_S3_P0 at (B 4) is labeled only once in the design.
Signal FM_PVDDCR_CPU0_P1_R_EN at (B 4) is labeled only once in the design.
Signal GPU_FPGA_EROT_RST_R_N at (B 4) is labeled only once in the design.
Signal PRSNT_SWB_ISO_R_N at (B 4) is labeled only once in the design.
Signal FM_PWRGD_PVDDCR_CPU1_P1 at (B 4) is labeled only once in the design.
Signal GPU_FPGA_EROT_RECOV_R_N at (A 4) is labeled only once in the design.
Signal FM_PWRGD_PVDDCR_CPU0_P1 at (A 4) is labeled only once in the design.
Signal P12V_SCM_PWRGD_R at (A 4) is labeled only once in the design.
Signal   FM_GPU_PWR_EN at (A 4) is labeled only once in the design.
Signal  GPU_FPGA_RST_N at (A 4) is labeled only once in the design.
Signal FM_FPGA_DEBUG_SW_SPARE at (A 4) is labeled only once in the design.
Signal FM_PVDD33_S5_EN at (A 4) is labeled only once in the design.
Signal FM_CPU0_PWR_GOOD at (A 4) is labeled only once in the design.
Signal FM_PVDDIO_P1_EN at (A 4) is labeled only once in the design.
Signal FM_PWRGD_PVDDIO_P1 at (A 4) is labeled only once in the design.
Signal FM_GPU_HSC_EN_R at (A 4) is labeled only once in the design.
Signal P12V_E1S_0_PWRGD at (A 4) is labeled only once in the design.
Signal FM_PLD_OCP_SFF_PWR_GOOD_R at (A 4) is labeled only once in the design.
Signal P0V9_RETIMER_CPU0_EN_R2 at (A 4) is labeled only once in the design.
Signal   P12V_E1S_0_EN at (A 4) is labeled only once in the design.
Signal HPDB_HSC_PWRGD_ISO_R at (A 4) is labeled only once in the design.
Signal P3V3_E1S_0_EN_R at (A 4) is labeled only once in the design.

Warnings in Page : @t6g_mb_lib.t6g(sch_1):Page82
Signal PWRGD_OCP_SFF_PWR_GOOD at (B 3) is labeled only once in the design.
Signal FM_PLD_OCP_SFF_MAIN_PWR_EN_R at (B 3) is labeled only once in the design.
Signal FM_CPU0_CORETYPE2 at (B 3) is labeled only once in the design.
Signal     FM_CLR_CMOS at (B 3) is labeled only once in the design.
Signal OCP_V3_2_P3V3_P12V_ADC_ALERT at (B 3) is labeled only once in the design.
Signal E1S_0_P3V3_P12V_ADC_ALERT at (B 4) is labeled only once in the design.
Signal FM_PLD_OCP_SFF_AUX_PWR_R_EN at (B 3) is labeled only once in the design.
Signal FM_CLKREQ_M2_1_N at (B 3) is labeled only once in the design.
Signal FM_PDB_BUF_EN_N at (B 4) is labeled only once in the design.
Signal   FM_CPU1_SP5R3 at (B 4) is labeled only once in the design.
Signal FM_PVDDCR_CPU1_P1_OCP_N at (B 4) is labeled only once in the design.
Signal FM_INT_CPU0_HP_UBM_R_N at (B 3) is labeled only once in the design.
Signal FM_PVDD11_S3_P0_EN at (B 3) is labeled only once in the design.
Signal   FM_CPU1_SP5R4 at (B 4) is labeled only once in the design.
Signal FM_CPU0_PROCHOT_R_N at (B 3) is labeled only once in the design.
Signal FM_PVDDCR_CPU0_P1_OCP_N at (B 3) is labeled only once in the design.
Signal     FM_CPU1_SA0 at (B 3) is labeled only once in the design.
Signal FM_PVDD11_S3_P0_OCP_N at (B 3) is labeled only once in the design.
Signal FM_PVDD11_S3_P1_OCP_N at (B 3) is labeled only once in the design.
Signal FM_CPU1_PROCHOT_R_N at (B 3) is labeled only once in the design.
Signal     FM_CPU0_SA1 at (B 3) is labeled only once in the design.
Signal     FM_CPU0_SA0 at (B 3) is labeled only once in the design.
Signal FM_CPU0_CORETYPE0 at (B 3) is labeled only once in the design.
Signal FM_CPU1_XTRIG_L4 at (B 4) is labeled only once in the design.
Signal FM_CPU1_XTRIG_L5 at (B 4) is labeled only once in the design.
Signal   FM_CPU1_SP5R2 at (B 4) is labeled only once in the design.
Signal FM_CPU1_CORETYPE2 at (B 4) is labeled only once in the design.
Signal FM_APML_MUX2_SEL_R at (B 4) is labeled only once in the design.
Signal   FM_CPU1_SP5R1 at (B 4) is labeled only once in the design.
Signal   FM_CPU0_SP5R2 at (B 4) is labeled only once in the design.
Signal   FM_CPU0_SP5R1 at (B 4) is labeled only once in the design.
Signal FM_CPU1_CORETYPE1 at (B 4) is labeled only once in the design.
Signal FM_CPU0_CORETYPE1 at (B 4) is labeled only once in the design.
Signal FM_APML_MUX2_OE_R_N at (B 4) is labeled only once in the design.
Signal FM_PVDDCR_CPU1_P0_R_EN at (B 4) is labeled only once in the design.
Signal FM_CPU1_CORETYPE0 at (B 4) is labeled only once in the design.
Signal     FM_CPU1_SA1 at (B 4) is labeled only once in the design.
Signal FM_CPU1_XTRIG_L6 at (B 4) is labeled only once in the design.
Signal FM_BMC_TPM_PRES_N_R at (B 4) is labeled only once in the design.
Signal FM_PWRGD_PVDDCR_CPU1_P0 at (B 4) is labeled only once in the design.
Signal   FM_CPU0_SP5R3 at (B 4) is labeled only once in the design.
Signal FM_PVDDCR_CPU1_P0_OCP_N at (B 4) is labeled only once in the design.
Signal FM_PVDDCR_CPU0_P0_OCP_N at (B 4) is labeled only once in the design.
Signal FM_SMM_CRASHDUMP_R at (B 4) is labeled only once in the design.
Signal IRQ_BMC_SMI_R_N at (B 4) is labeled only once in the design.
Signal FM_CPU0_XTRIG_L6 at (B 4) is labeled only once in the design.
Signal FM_PRSNT_CPU1_R_N at (B 3) is labeled only once in the design.
Signal FM_PRSNT_CPU0_R_N at (B 3) is labeled only once in the design.
Signal   FM_CPU0_SP5R4 at (B 3) is labeled only once in the design.
Signal E1S_0_PRSNT_R_N at (B 3) is labeled only once in the design.
Signal P12V_OCP_V3_1_PWRGD at (B 3) is labeled only once in the design.
Signal FM_PVDDCR_CPU1_P1_R_EN at (B 3) is labeled only once in the design.
Signal OCP_SFF_P3V3_P12V_ADC_ALERT at (B 3) is labeled only once in the design.
Signal FM_SEC_MUX_OE_R_N at (B 4) is labeled only once in the design.
Signal FM_SEC_MUX_R_SEL at (B 4) is labeled only once in the design.
Signal FM_CPU1_XTRIG_L7 at (B 4) is labeled only once in the design.
Signal IRQ_CPU_BMC_NMI_R_N at (B 4) is labeled only once in the design.
Signal FM_CPU0_XTRIG_L5 at (B 4) is labeled only once in the design.
Signal FM_CPU0_XTRIG_L4 at (B 4) is labeled only once in the design.
Signal IRQ_SMI_ACTIVE_N_R at (B 4) is labeled only once in the design.
Signal IRQ_TPM_SPI_R1_N at (B 4) is labeled only once in the design.
Signal FM_CPU0_XTRIG_L7 at (B 4) is labeled only once in the design.
Signal FM_BMC_READY_R_N at (B 4) is labeled only once in the design.
Signal FM_CPU1_BMC_RST_R_N at (B 4) is labeled only once in the design.

Warnings in Page : @t6g_mb_lib.t6g(sch_1):Page84
Signal     SCM_IRQ_R_N at (B 1) is labeled only once in the design.

Warnings in Page : @t6g_mb_lib.t6g(sch_1):Page85
Signal    JTAG_PLD_TMS at (A 2) is labeled only once in the design.
Signal    JTAG_PLD_TDI at (A 2) is labeled only once in the design.
Signal    JTAG_PLD_TDO at (A 2) is labeled only once in the design.
Signal    JTAG_PLD_TCK at (A 2) is labeled only once in the design.
Signal BMC_FPGA_LED2_N at (B 2) is labeled only once in the design.
Signal BMC_FPGA_LED1_N at (B 2) is labeled only once in the design.
Signal BMC_FPGA_LED2_R_N at (B 2) is labeled only once in the design.
Signal BMC_FPGA_LED1_R_N at (B 2) is labeled only once in the design.
Signal PWRGD_P5V_AUX_R1 at (B 2) is labeled only once in the design.
Signal PWRGD_P5V_AUX_R2 at (B 2) is labeled only once in the design.
Signal   IRQ_HSC_FAULT at (B 4) is labeled only once in the design.

Warnings in Page : @t6g_mb_lib.t6g(sch_1):Page86
Signal I3C_SPD_DDRA_CPU0_SDA at (B 4) is labeled only once in the design.
Signal I3C_SPD_DDRA_CPU0_SCL at (B 4) is labeled only once in the design.
Signal PWRGD_CHA_CPU0_DIMM0 at (A 4) is labeled only once in the design.
Signal PWRGD_CHAF_CPU0_R1 at (A 2) is labeled only once in the design.

Warnings in Page : @t6g_mb_lib.t6g(sch_1):Page87
Signal PWRGD_CHB_CPU0_DIMM at (B 4) is labeled only once in the design.
Signal I3C_SPD_DDRB_CPU0_SDA at (B 4) is labeled only once in the design.
Signal I3C_SPD_DDRB_CPU0_SCL at (B 4) is labeled only once in the design.

Warnings in Page : @t6g_mb_lib.t6g(sch_1):Page88
Signal PWRGD_CHC_CPU0_DIMM at (B 4) is labeled only once in the design.
Signal I3C_SPD_DDRC_CPU0_SCL at (B 4) is labeled only once in the design.
Signal I3C_SPD_DDRC_CPU0_SDA at (B 4) is labeled only once in the design.

Warnings in Page : @t6g_mb_lib.t6g(sch_1):Page89
Signal PWRGD_CHD_CPU0_DIMM at (B 4) is labeled only once in the design.
Signal I3C_SPD_DDRD_CPU0_SCL at (B 4) is labeled only once in the design.
Signal I3C_SPD_DDRD_CPU0_SDA at (B 4) is labeled only once in the design.

Warnings in Page : @t6g_mb_lib.t6g(sch_1):Page90
Signal PWRGD_CHE_CPU0_DIMM at (B 4) is labeled only once in the design.
Signal I3C_SPD_DDRE_CPU0_SDA at (B 4) is labeled only once in the design.
Signal I3C_SPD_DDRE_CPU0_SCL at (B 4) is labeled only once in the design.

Warnings in Page : @t6g_mb_lib.t6g(sch_1):Page91
Signal I3C_SPD_DDRF_CPU0_SDA at (B 4) is labeled only once in the design.
Signal I3C_SPD_DDRF_CPU0_SCL at (B 4) is labeled only once in the design.
Signal PWRGD_CHF_CPU0_DIMM at (B 4) is labeled only once in the design.

Warnings in Page : @t6g_mb_lib.t6g(sch_1):Page92
Signal PWRGD_CHGL_CPU0_R1 at (A 2) is labeled only once in the design.
Signal I3C_SPD_DDRG_CPU0_SDA at (B 4) is labeled only once in the design.
Signal PWRGD_CHG_CPU0_DIMM0 at (B 4) is labeled only once in the design.
Signal I3C_SPD_DDRG_CPU0_SCL at (B 4) is labeled only once in the design.

Warnings in Page : @t6g_mb_lib.t6g(sch_1):Page93
Signal PWRGD_CHH_CPU0_DIMM at (B 4) is labeled only once in the design.
Signal I3C_SPD_DDRH_CPU0_SDA at (B 4) is labeled only once in the design.
Signal I3C_SPD_DDRH_CPU0_SCL at (B 4) is labeled only once in the design.

Warnings in Page : @t6g_mb_lib.t6g(sch_1):Page94
Signal I3C_SPD_DDRI_CPU0_SDA at (B 4) is labeled only once in the design.
Signal I3C_SPD_DDRI_CPU0_SCL at (B 4) is labeled only once in the design.
Signal PWRGD_CHI_CPU0_DIMM at (B 4) is labeled only once in the design.

Warnings in Page : @t6g_mb_lib.t6g(sch_1):Page95
Signal I3C_SPD_DDRJ_CPU0_SCL at (B 4) is labeled only once in the design.
Signal PWRGD_CHJ_CPU0_DIMM at (A 4) is labeled only once in the design.
Signal I3C_SPD_DDRJ_CPU0_SDA at (B 4) is labeled only once in the design.

Warnings in Page : @t6g_mb_lib.t6g(sch_1):Page96
Signal PWRGD_CHK_CPU0_DIMM at (B 4) is labeled only once in the design.
Signal I3C_SPD_DDRK_CPU0_SCL at (B 4) is labeled only once in the design.
Signal I3C_SPD_DDRK_CPU0_SDA at (B 4) is labeled only once in the design.

Warnings in Page : @t6g_mb_lib.t6g(sch_1):Page97
Signal PWRGD_CHL_CPU0_DIMM at (A 4) is labeled only once in the design.
Signal I3C_SPD_DDRL_CPU0_SCL at (A 4) is labeled only once in the design.
Signal I3C_SPD_DDRL_CPU0_SDA at (B 4) is labeled only once in the design.

Warnings in Page : @t6g_mb_lib.t6g(sch_1):Page98
Signal PWRGD_CHAF_CPU1_R1 at (A 2) is labeled only once in the design.
Signal PWRGD_CHA_CPU1_DIMM0 at (B 4) is labeled only once in the design.
Signal I3C_SPD_DDRA_CPU1_SCL at (B 4) is labeled only once in the design.
Signal I3C_SPD_DDRA_CPU1_SDA at (B 4) is labeled only once in the design.

Warnings in Page : @t6g_mb_lib.t6g(sch_1):Page99
Signal I3C_SPD_DDRB_CPU1_SDA at (B 4) is labeled only once in the design.
Signal I3C_SPD_DDRB_CPU1_SCL at (B 4) is labeled only once in the design.
Signal PWRGD_CHB_CPU1_DIMM at (B 4) is labeled only once in the design.
Signal PWRGD_CHAF_CPU1 at (A 4) has too little display space.

Warnings in Page : @t6g_mb_lib.t6g(sch_1):Page100
Signal PWRGD_CHC_CPU1_DIMM at (A 4) is labeled only once in the design.
Signal I3C_SPD_DDRC_CPU1_SDA at (B 4) is labeled only once in the design.
Signal I3C_SPD_DDRC_CPU1_SCL at (B 4) is labeled only once in the design.

Warnings in Page : @t6g_mb_lib.t6g(sch_1):Page101
Signal PWRGD_CHD_CPU1_DIMM at (B 4) is labeled only once in the design.
Signal I3C_SPD_DDRD_CPU1_SCL at (B 4) is labeled only once in the design.
Signal I3C_SPD_DDRD_CPU1_SDA at (B 4) is labeled only once in the design.

Warnings in Page : @t6g_mb_lib.t6g(sch_1):Page102
Signal PWRGD_CHE_CPU1_DIMM at (B 4) is labeled only once in the design.
Signal I3C_SPD_DDRE_CPU1_SDA at (B 4) is labeled only once in the design.
Signal I3C_SPD_DDRE_CPU1_SCL at (B 4) is labeled only once in the design.

Warnings in Page : @t6g_mb_lib.t6g(sch_1):Page103
Signal PWRGD_CHF_CPU1_DIMM at (B 4) is labeled only once in the design.
Signal I3C_SPD_DDRF_CPU1_SDA at (B 4) is labeled only once in the design.
Signal I3C_SPD_DDRF_CPU1_SCL at (B 4) is labeled only once in the design.

Warnings in Page : @t6g_mb_lib.t6g(sch_1):Page104
Signal PWRGD_CHGL_CPU1_R1 at (A 2) is labeled only once in the design.
Signal PWRGD_CHG_CPU1_DIMM0 at (B 4) is labeled only once in the design.
Signal I3C_SPD_DDRG_CPU1_SDA at (B 4) is labeled only once in the design.
Signal I3C_SPD_DDRG_CPU1_SCL at (B 4) is labeled only once in the design.

Warnings in Page : @t6g_mb_lib.t6g(sch_1):Page105
Signal PWRGD_CHH_CPU1_DIMM at (B 4) is labeled only once in the design.
Signal I3C_SPD_DDRH_CPU1_SDA at (B 4) is labeled only once in the design.
Signal I3C_SPD_DDRH_CPU1_SCL at (B 4) is labeled only once in the design.

Warnings in Page : @t6g_mb_lib.t6g(sch_1):Page106
Signal I3C_SPD_DDRI_CPU1_SDA at (B 4) is labeled only once in the design.
Signal I3C_SPD_DDRI_CPU1_SCL at (B 4) is labeled only once in the design.
Signal PWRGD_CHI_CPU1_DIMM at (B 4) is labeled only once in the design.

Warnings in Page : @t6g_mb_lib.t6g(sch_1):Page107
Signal PWRGD_CHJ_CPU1_DIMM at (A 4) is labeled only once in the design.
Signal I3C_SPD_DDRJ_CPU1_SCL at (B 4) is labeled only once in the design.
Signal I3C_SPD_DDRJ_CPU1_SDA at (B 4) is labeled only once in the design.

Warnings in Page : @t6g_mb_lib.t6g(sch_1):Page108
Signal I3C_SPD_DDRK_CPU1_SCL at (B 4) is labeled only once in the design.
Signal I3C_SPD_DDRK_CPU1_SDA at (B 4) is labeled only once in the design.
Signal PWRGD_CHK_CPU1_DIMM at (A 4) is labeled only once in the design.

Warnings in Page : @t6g_mb_lib.t6g(sch_1):Page109
Signal PWRGD_CHL_CPU1_DIMM at (B 4) is labeled only once in the design.
Signal I3C_SPD_DDRL_CPU1_SDA at (B 4) is labeled only once in the design.
Signal I3C_SPD_DDRL_CPU1_SCL at (B 4) is labeled only once in the design.

Warnings in Page : @t6g_mb_lib.t6g(sch_1):Page111
Signal     FM_P2E_EN_N at (B 3) is labeled only once in the design.
Signal         PU_TEST at (B 3) is labeled only once in the design.

Warnings in Page : @t6g_mb_lib.t6g(sch_1):Page112
Signal    FM_P2E_EN2_N at (B 2) is labeled only once in the design.
Signal PD_P2E_BUF2_ENSMB at (B 4) is labeled only once in the design.
Signal        BUF2_VDD at (B 4) is labeled only once in the design.
Signal          NC_RES at (B 2) is labeled only once in the design.

Warnings in Page : @t6g_mb_lib.t6g(sch_1):Page116
Signal      NC_J106_A5 at (B 4) is labeled only once in the design.

Warnings in Page : @t6g_mb_lib.t6g(sch_1):Page117
Signal      NC_J107_N6 at (B 4) is labeled only once in the design.
Signal      NC_J107_A3 at (B 2) is labeled only once in the design.
Signal      NC_J107_A5 at (B 4) is labeled only once in the design.
Signal      NC_J107_N4 at (B 2) is labeled only once in the design.
Signal      NC_J107_A1 at (B 2) is labeled only once in the design.

Warnings in Page : @t6g_mb_lib.t6g(sch_1):Page118
Signal      NC_J108_N4 at (B 2) is labeled only once in the design.
Signal      NC_J108_N2 at (B 2) is labeled only once in the design.
Signal      NC_J108_N6 at (B 4) is labeled only once in the design.

Warnings in Page : @t6g_mb_lib.t6g(sch_1):Page122
Signal      NC_J112_P5 at (A 4) is labeled only once in the design.
Signal      NC_J112_R5 at (A 4) is labeled only once in the design.
Signal      NC_J112_O2 at (B 2) is labeled only once in the design.
Signal      NC_J112_N2 at (B 2) is labeled only once in the design.
Signal      NC_J112_S5 at (A 4) is labeled only once in the design.
Signal      NC_J112_O5 at (A 4) is labeled only once in the design.

Warnings in Page : @t6g_mb_lib.t6g(sch_1):Page123
Signal PRSNT_CABLE_GPU_A3 at (B 2) is labeled only once in the design.
Signal PRSNT_CABLE_SWB_B1 at (B 4) is labeled only once in the design.
Signal       PRSNT_SWB at (B 4) is labeled only once in the design.
Signal PRSNT_CABLE_SWB_B2 at (A 4) is labeled only once in the design.

Warnings in Page : @t6g_mb_lib.t6g(sch_1):Page124
Signal SWB_HSC_EN_BUF_R at (B 2) is labeled only once in the design.
Signal      HGX_DETECT at (A 4) is labeled only once in the design.
Signal GPU_3V3IO_RSVD4_N at (B 4) is labeled only once in the design.
Signal GPU_3V3IO_RSVD3_N at (B 4) is labeled only once in the design.
Signal GPU_3V3IO_RSVD1_N at (B 4) is labeled only once in the design.
Signal      NC_U316_2Y at (B 1) is labeled only once in the design.

Warnings in Page : @t6g_mb_lib.t6g(sch_1):Page125
Signal GPU_3V3IO_RSVD1_FFU_N at (B 4) is labeled only once in the design.
Signal GPU_3V3IO_RSVD3_FFU_N at (B 2) is labeled only once in the design.
Signal PRSNT_CABLE_GPU_A2 at (B 2) is labeled only once in the design.
Signal GPU_3V3IO_RSVD5_FFU_N at (B 2) is labeled only once in the design.
Signal GPU_3V3IO_RSVD0_FFU_N at (B 4) is labeled only once in the design.
Signal PRSNT_CABLE_GPU_B3 at (B 4) is labeled only once in the design.
Signal SWB_HSC_PWRGD_N at (A 2) is labeled only once in the design.
Signal PRSNT_CABLE_GPU_A1 at (A 4) is labeled only once in the design.

Warnings in Page : @t6g_mb_lib.t6g(sch_1):Page126
Signal GPU_WP_HW_CTRL_ISO at (B 2) is labeled only once in the design.
Signal GPU_FPGA_EROT_FATALERR at (A 2) is labeled only once in the design.
Signal GPU_FPGA_THERM_OVERT at (B 4) is labeled only once in the design.
Signal   GPU_HMC_PRSNT at (B 4) is labeled only once in the design.
Signal GPU_BASE_HMC_READY_N at (B 4) is labeled only once in the design.
Signal  GPU_FPGA_OVERT at (A 4) is labeled only once in the design.

Warnings in Page : @t6g_mb_lib.t6g(sch_1):Page127
Signal FM_SMB_2_ALERT_GPU at (B 2) is labeled only once in the design.
Signal  FM_SWB_PWRGD_N at (B 2) is labeled only once in the design.
Signal FM_SMB_1_ALERT_GPU at (A 4) is labeled only once in the design.
Signal  FM_GPU_PWRGD_N at (B 2) is labeled only once in the design.
Signal RST_BMC_FROM_SWB at (B 4) is labeled only once in the design.
Signal   BIC_MONITER_N at (B 4) is labeled only once in the design.
Signal FM_SWB_BIC_READY at (B 4) is labeled only once in the design.

Warnings in Page : @t6g_mb_lib.t6g(sch_1):Page128
Signal GPU_FPGA_BOOT_EN_BUF_R at (B 3) is labeled only once in the design.
Signal GPU_BASE_STBY_EN_BUF_R at (B 3) is labeled only once in the design.
Signal FM_SWB_PWR_EN_R1_BUF at (A 2) is labeled only once in the design.
Signal RST_PERST_0_SWB_BUF_R_N at (B 3) is labeled only once in the design.
Signal RST_PERST_2_SWB_BUF_R_N at (B 3) is labeled only once in the design.
Signal RST_PERST_1_SWB_BUF_R_N at (A 3) is labeled only once in the design.

Warnings in Page : @t6g_mb_lib.t6g(sch_1):Page129
Signal GPU_FPGA_EROT_RST_BUF_R_N at (B 3) is labeled only once in the design.
Signal      NC_U257_2Y at (B 2) is labeled only once in the design.
Signal GPU_FPGA_EROT_RECOV_BUF_R_N at (B 3) is labeled only once in the design.
Signal GPU_NVS_PWR_BRAKE_N_R at (B 3) is labeled only once in the design.

Warnings in Page : @t6g_mb_lib.t6g(sch_1):Page130
Signal GPU_FPGA_RST_R1_BUF_N at (A 3) is labeled only once in the design.
Signal UART_BMC_BIC_R_BUF_RX at (A 3) is labeled only once in the design.
Signal      FM_UART_EN at (A 3) is labeled only once in the design.
Signal UART_BMC_BIC_R_RX at (A 3) is labeled only once in the design.
Signal BMC_MONITER_BUF_R at (B 3) is labeled only once in the design.
Signal FM_GPU_PWR_EN_R1 at (B 3) is labeled only once in the design.
Signal RST_SWB_BIC_BUF_R_N at (B 3) is labeled only once in the design.

Warnings in Page : @t6g_mb_lib.t6g(sch_1):Page131
Signal OCP_SFF_PRSNTA_R_N at (B 2) is labeled only once in the design.
Signal     USB2_P11_DP at (A 2) is labeled only once in the design.
Signal     USB2_P11_DN at (A 2) is labeled only once in the design.
Signal OCP_SFF_BIF0_R_N at (B 4) is labeled only once in the design.
Signal SMB_OCP_SFF_3V3AUX_BUF_R_SCL at (B 2) is labeled only once in the design.
Signal SMB_OCP_SFF_3V3AUX_BUF_R_SDA at (B 2) is labeled only once in the design.
Signal  TP_OCP_SFF_B69 at (A 4) is labeled only once in the design.
Signal  TP_OCP_SFF_B68 at (A 4) is labeled only once in the design.
Signal OCP_SFF_BIF1_R_N at (B 4) is labeled only once in the design.
Signal OCP_SFF_AUX_PWR_EN_R at (B 4) is labeled only once in the design.
Signal OCP_SFF_BIF2_R_N at (B 4) is labeled only once in the design.
Signal OCP_SFF_MAIN_PWR_EN_R at (B 4) is labeled only once in the design.

Warnings in Page : @t6g_mb_lib.t6g(sch_1):Page132
Signal NCSI_BMC_TXD0_R at (B 2) is labeled only once in the design.
Signal NCSI_BMC_CRS_DV_R at (B 2) is labeled only once in the design.
Signal OCP_SFF_RBT_ARB_IN_R at (B 2) is labeled only once in the design.
Signal NCSI_BMC_TXD1_R at (B 2) is labeled only once in the design.
Signal NCSI_BMC_RXD1_R at (B 2) is labeled only once in the design.
Signal NCSI_BMC_RXD0_R at (B 2) is labeled only once in the design.
Signal NCSI_BMC_TX_EN_R at (B 2) is labeled only once in the design.
Signal FB_BMC_ISOLATE_R1 at (B 3) is labeled only once in the design.
Signal OCP_SFF_AUX_PWR_EN_R1 at (B 4) is labeled only once in the design.
Signal OCP_SFF_AUX_PWR_EN_R2 at (A 4) is labeled only once in the design.
Signal RST_HP_OCP_SFF_R_N at (A 3) is labeled only once in the design.

Warnings in Page : @t6g_mb_lib.t6g(sch_1):Page133
Signal OCP_SFF_PWRBRK_BUFF_N at (B 3) is labeled only once in the design.
Signal     NC_U157_NC1 at (B 3) is labeled only once in the design.
Signal CLK_50M_NCSI_OCP_SFF_ISO_R at (A 2) is labeled only once in the design.
Signal IRQ_LVC3_WAKE_BUF_N at (B 2) is labeled only once in the design.
Signal OCP_SFF_WAKE_BUFF_R_N at (B 3) is labeled only once in the design.
Signal OCP_SFF_WAKE_BUFF_N at (B 4) is labeled only once in the design.
Signal  CLK_50M_RMII_R at (A 4) is labeled only once in the design.
Signal     NC_U104_NC1 at (B 4) is labeled only once in the design.
Signal PU_OCP_SFF_WAKE_OE at (B 4) is labeled only once in the design.
Signal      CLK_50M_EN at (A 4) is labeled only once in the design.
Signal CLK_50M_NCSI_OCP_2 at (A 3) is labeled only once in the design.
Signal   TP_CLK_50M_Y3 at (A 3) is labeled only once in the design.
Signal CLK_50M_NCSI_OCP_1 at (A 3) is labeled only once in the design.
Signal CLK_50M_BMC_MAC_R at (A 3) is labeled only once in the design.
Signal    CLK_50M_RMII at (A 4) is labeled only once in the design.
Signal RST_PERST_OCP_SFF_BUF2_N at (B 4) is labeled only once in the design.

Warnings in Page : @t6g_mb_lib.t6g(sch_1):Page134
Signal   P3V3_OCP_UV_1 at (B 2) is labeled only once in the design.
Signal  P3V3_OCP_REG_1 at (B 3) is labeled only once in the design.
Signal P3V3_OCP_UV_1_R1 at (B 3) is labeled only once in the design.
Signal P12V_OCP_1_EN_G at (B 4) is labeled only once in the design.
Signal P12V_OCP_EN_1_R at (A 4) is labeled only once in the design.
Signal P3V3_OCP_PWRGD_1 at (B 2) is labeled only once in the design.
Signal P3V3_OCP_GATE_PU202_1 at (B 2) is labeled only once in the design.
Signal   P12V_OCP_OV_1 at (B 3) is labeled only once in the design.
Signal   P12V_OCP_CB_1 at (B 3) is labeled only once in the design.
Signal   P12V_OCP_UV_1 at (B 3) is labeled only once in the design.
Signal   P3V3_OCP_CB_1 at (B 2) is labeled only once in the design.
Signal  P3V3_OCP_VCC_1 at (B 3) is labeled only once in the design.
Signal HP_LVC3_OCP_V3_1_PRSNT2_N_R at (A 3) is labeled only once in the design.
Signal   P3V3_OCP_OV_1 at (B 2) is labeled only once in the design.
Signal  P12V_OCP_REG_1 at (B 3) is labeled only once in the design.
Signal P3V3_OCP_1_EN_G at (B 4) is labeled only once in the design.
Signal P12V_OCP_UV_1_R at (B 4) is labeled only once in the design.
Signal P12V_OCP_SENSE_1 at (B 2) is labeled only once in the design.
Signal P3V3_OCP_FAULT_1 at (B 2) is labeled only once in the design.
Signal  P12V_OCP_VCC_1 at (B 3) is labeled only once in the design.
Signal P3V3_OCP_SENSE_1 at (B 2) is labeled only once in the design.
Signal P3V3_OCP_EN_1_R at (B 4) is labeled only once in the design.
Signal P12V_OCP_GATE_1 at (B 2) is labeled only once in the design.
Signal P12V_OCP_PWRGD_1 at (B 2) is labeled only once in the design.
Signal P12V_OCP_FAULT_1 at (B 2) is labeled only once in the design.
Signal P12V_OCP_SFF_BUF_EN_R at (B 4) has too little display space.

Warnings in Page : @t6g_mb_lib.t6g(sch_1):Page135
Signal   P12V_OCP_SS_1 at (A 4) is labeled only once in the design.
Signal P12V_OCP_EN_1_R2 at (A 4) is labeled only once in the design.
Signal P12V_OCP_OV_FB_1 at (A 3) is labeled only once in the design.
Signal P3V3_OCP_MODE_1 at (B 2) is labeled only once in the design.
Signal P3V3_OCP_ILIMIT_1 at (B 2) is labeled only once in the design.
Signal P3V3_OCP_GATE_1 at (B 1) is labeled only once in the design.
Signal P3V3_OCP_DVDT_1 at (B 2) is labeled only once in the design.
Signal P12V_OCP_IMON_1 at (A 3) is labeled only once in the design.
Signal P12V_OCP_FLTB_1 at (A 3) is labeled only once in the design.
Signal P12V_OCP_TIMER_1 at (A 4) is labeled only once in the design.
Signal P12V_OCP_ISET_1 at (A 4) is labeled only once in the design.
Signal P3V3_OCP_EN_1_R2 at (B 2) is labeled only once in the design.

Warnings in Page : @t6g_mb_lib.t6g(sch_1):Page136
Signal OCP_V3_1_P3V3_R1_PWRGD at (A 4) is labeled only once in the design.
Signal OCP_V3_1_P3V3_R3_PWRGD at (B 3) is labeled only once in the design.
Signal HP_LVC3_OCP_V3_1_PWRGD at (B 3) is labeled only once in the design.
Signal RST_PERST_OCP_SFF_BUF_R_N at (B 2) is labeled only once in the design.
Signal OCP_V3_1_P3V3_R2_PWRGD at (B 3) is labeled only once in the design.
Signal OCP_V3_1_P3V3_PLD_PWRGD at (B 2) is labeled only once in the design.
Signal P12V_OCP_SFF_BUF_EN at (B 3) is labeled only once in the design.
Signal OCP_SFF_AUX_PWR_EN_R3 at (A 2) is labeled only once in the design.
Signal HP_LVC3_OCP_V3_1_P12V_R_PWRGD at (B 4) is labeled only once in the design.
Signal HP_LVC3_OCP_V3_1_PWRGD_R2 at (B 4) is labeled only once in the design.
Signal HP_LVC3_OCP_V3_1_PWRGD_R1 at (A 3) is labeled only once in the design.
Signal RST_PERST_OCP_SFF_R_N at (B 3) is labeled only once in the design.
Signal P12V_OCP_V3_1_PLD_R_PWRGD at (B 4) is labeled only once in the design.
Signal P12V_OCP_SFF_EN_R3 at (B 3) is labeled only once in the design.
Signal HP_LVC3_OCP_SFF_PRSNT2 at (B 4) is labeled only once in the design.

Warnings in Page : @t6g_mb_lib.t6g(sch_1):Page137
Signal OCP_V3_2_BIF0_R_N at (B 4) is labeled only once in the design.
Signal OCP_V3_2_BIF1_R_N at (B 4) is labeled only once in the design.
Signal OCP_V3_2_BIF2_R_N at (B 4) is labeled only once in the design.
Signal OCP_V3_2_PRSNTA_R_N at (B 2) is labeled only once in the design.
Signal SMB_OCP_V3_2_3V3AUX_BUF_R_SDA at (B 2) is labeled only once in the design.
Signal SMB_OCP_V3_2_3V3AUX_BUF_R_SCL at (B 2) is labeled only once in the design.
Signal TP_OCP_V3_2_B68 at (A 4) is labeled only once in the design.
Signal     USB2_P10_DN at (A 2) is labeled only once in the design.
Signal     USB2_P10_DP at (A 2) is labeled only once in the design.
Signal OCP_V3_2_MAIN_PWR_EN_R at (B 4) is labeled only once in the design.
Signal OCP_V3_2_AUX_PWR_EN_R at (B 4) is labeled only once in the design.
Signal TP_OCP_V3_2_B69 at (A 4) is labeled only once in the design.

Warnings in Page : @t6g_mb_lib.t6g(sch_1):Page138
Signal NCSI_BMC_CRS_DV_R1 at (B 2) is labeled only once in the design.
Signal NCSI_BMC_RXD0_R1 at (B 2) is labeled only once in the design.
Signal OCP_V3_2_RBT_ARB_IN_R at (B 2) is labeled only once in the design.
Signal NCSI_BMC_TXD1_R1 at (B 2) is labeled only once in the design.
Signal NCSI_BMC_TXD0_R1 at (B 2) is labeled only once in the design.
Signal NCSI_BMC_TX_EN_R1 at (B 2) is labeled only once in the design.
Signal OCP_V3_2_AUX_PWR_EN_R1 at (B 4) is labeled only once in the design.
Signal NCSI_BMC_RXD1_R1 at (B 2) is labeled only once in the design.
Signal FB_BMC_ISOLATE_R2 at (B 3) is labeled only once in the design.

Warnings in Page : @t6g_mb_lib.t6g(sch_1):Page139
Signal OCP_V3_2_WAKE_BUFF_R_N at (B 3) is labeled only once in the design.
Signal IRQ_LVC3_V3_2_WAKE_BUF_N at (B 2) is labeled only once in the design.
Signal     NC_U219_NC1 at (B 3) is labeled only once in the design.
Signal RST_HP_OCP_V3_2_R_N at (A 3) is labeled only once in the design.
Signal OCP_V3_2_WAKE_BUFF_N at (B 4) is labeled only once in the design.
Signal     NC_U218_NC1 at (B 4) is labeled only once in the design.
Signal OCP_V3_2_AUX_PWR_EN_R3 at (A 4) is labeled only once in the design.
Signal PU_OCP_V3_2_WAKE_OE at (B 4) is labeled only once in the design.
Signal OCP_V3_2_PWRBRK_BUFF_N at (B 3) is labeled only once in the design.
Signal CLK_50M_NCSI_OCP_V3_2_ISO_R at (A 2) is labeled only once in the design.
Signal RST_PERST_OCP_V3_2_BUF2_N at (B 4) is labeled only once in the design.

Warnings in Page : @t6g_mb_lib.t6g(sch_1):Page140
Signal P3V3_OCP_EN_2_R at (B 4) is labeled only once in the design.
Signal P12V_OCP_EN_2_R at (A 4) is labeled only once in the design.
Signal P12V_OCP_2_EN_G at (B 4) is labeled only once in the design.
Signal  P12V_OCP_VCC_2 at (B 3) is labeled only once in the design.
Signal P12V_OCP_PWRGD_2 at (B 2) is labeled only once in the design.
Signal P12V_OCP_SENSE_2 at (B 2) is labeled only once in the design.
Signal P12V_OCP_FAULT_2 at (B 2) is labeled only once in the design.
Signal P12V_OCP_GATE_2 at (B 2) is labeled only once in the design.
Signal P3V3_OCP_2_EN_G at (B 4) is labeled only once in the design.
Signal   P3V3_OCP_UV_2 at (B 3) is labeled only once in the design.
Signal  P3V3_OCP_REG_2 at (B 3) is labeled only once in the design.
Signal  P3V3_OCP_VCC_2 at (B 3) is labeled only once in the design.
Signal   P3V3_OCP_CB_2 at (B 3) is labeled only once in the design.
Signal P3V3_OCP_PWRGD_2 at (B 2) is labeled only once in the design.
Signal HP_LVC3_OCP_V3_2_PRSNT2_N_R at (A 3) is labeled only once in the design.
Signal P3V3_OCP_FAULT_2 at (B 2) is labeled only once in the design.
Signal P3V3_OCP_SENSE_2 at (B 2) is labeled only once in the design.
Signal   P3V3_OCP_OV_2 at (B 3) is labeled only once in the design.
Signal P3V3_OCP_GATE_2 at (B 2) is labeled only once in the design.
Signal P3V3_OCP_UV_2_R1 at (B 4) is labeled only once in the design.
Signal   P12V_OCP_CB_2 at (B 3) is labeled only once in the design.
Signal   P12V_OCP_OV_2 at (B 3) is labeled only once in the design.
Signal  P12V_OCP_REG_2 at (B 3) is labeled only once in the design.
Signal   P12V_OCP_UV_2 at (B 3) is labeled only once in the design.
Signal P12V_OCP_UV_2_R at (B 4) is labeled only once in the design.

Warnings in Page : @t6g_mb_lib.t6g(sch_1):Page141
Signal   P3V3_OCP_EN_2 at (B 2) is labeled only once in the design.
Signal P12V_OCP_ISET_2 at (A 4) is labeled only once in the design.
Signal   P12V_OCP_SS_2 at (A 4) is labeled only once in the design.
Signal P12V_OCP_TIMER_2 at (A 4) is labeled only once in the design.
Signal P12V_OCP_V3_2_EN_2_R3 at (A 4) is labeled only once in the design.
Signal P12V_OCP_FLTB_2 at (A 3) is labeled only once in the design.
Signal P12V_OCP_OV_FB_2 at (A 3) is labeled only once in the design.
Signal P12V_OCP_IMON_2 at (A 3) is labeled only once in the design.
Signal P3V3_OCP_MODE_2 at (B 2) is labeled only once in the design.
Signal P3V3_OCP_ILIMIT_2 at (B 2) is labeled only once in the design.
Signal P3V3_OCP_DVDT_2 at (B 2) is labeled only once in the design.
Signal P3V3_OCP_GATE_PU207_2 at (B 1) is labeled only once in the design.

Warnings in Page : @t6g_mb_lib.t6g(sch_1):Page142
Signal P12V_OCP_V3_2_PLD_R_PWRGD at (B 3) is labeled only once in the design.
Signal HP_LVC3_OCP_V3_2_PWRGD_R2 at (B 4) is labeled only once in the design.
Signal OCP_V3_2_P3V3_R3_PWRGD at (B 3) is labeled only once in the design.
Signal RST_PERST_OCP_V3_2_BUF_R_N at (B 2) is labeled only once in the design.
Signal RST_PERST_OCP_V3_2_R_N at (B 3) is labeled only once in the design.
Signal OCP_V3_2_P3V3_R1_PWRGD at (A 4) is labeled only once in the design.
Signal HP_LVC3_OCP_V3_2_PWRGD at (B 3) is labeled only once in the design.
Signal OCP_V3_2_P3V3_PLD_PWRGD at (B 2) is labeled only once in the design.
Signal HP_LVC3_OCP_V3_2_P12V_R_PWRGD at (B 4) is labeled only once in the design.
Signal OCP_V3_2_P3V3_R2_PWRGD at (B 2) is labeled only once in the design.
Signal OCP_V3_2_AUX_PWR_EN_R2 at (A 2) is labeled only once in the design.
Signal HP_LVC3_OCP_V3_2_PWRGD_R1 at (A 3) is labeled only once in the design.
Signal HP_LVC3_OCP_V3_2_PRSNT2 at (B 4) is labeled only once in the design.
Signal P12V_OCP_V3_2_EN_R3 at (B 3) is labeled only once in the design.
Signal P12V_OCP_V3_2_BUF_EN at (B 3) is labeled only once in the design.

Warnings in Page : @t6g_mb_lib.t6g(sch_1):Page143
Signal OCP_SFF_PRSNT01_R1_N at (B 4) is labeled only once in the design.
Signal OCP_SFF_PRSNT23_R_N at (B 4) is labeled only once in the design.
Signal OCP_SFF_PRSNT_ALL_R1_N at (B 3) is labeled only once in the design.
Signal OCP_V3_2_PRSNT_ALL_R3_N at (A 3) is labeled only once in the design.
Signal OCP_SFF_RBT_ARB_IN_MUX2_R at (A 3) is labeled only once in the design.
Signal OCP_SFF_NOT_PRSNT_RBT_ARB_IN at (B 2) is labeled only once in the design.
Signal OCP_SFF_RBT_ARB_IN_MUX1_R at (B 3) is labeled only once in the design.
Signal OCP_SFF_PRSNT_ALL_R3_N at (B 3) is labeled only once in the design.
Signal OCP_V3_2_PRSNT_ALL_R1_N at (B 2) is labeled only once in the design.
Signal OCP_V3_2_NOT_PRSNT_RBT_ARB_IN at (B 2) is labeled only once in the design.
Signal OCP_V3_2_PRSNT_ALL_R_N at (B 3) is labeled only once in the design.
Signal OCP_SFF_PRSNT_ALL_R_N at (B 3) is labeled only once in the design.
Signal OCP_V3_2_PRSNT23_R_N at (B 4) is labeled only once in the design.
Signal OCP_V3_2_PRSNT01_R_N at (B 4) is labeled only once in the design.
Signal OCP_V3_2_PRSNT01_R1_N at (B 4) is labeled only once in the design.
Signal OCP_SFF_PRSNT01_R_N at (B 4) is labeled only once in the design.
Signal OCP_SFF_PRSNT23_R1_N at (B 4) is labeled only once in the design.
Signal OCP_V3_2_PRSNT23_R1_N at (B 4) is labeled only once in the design.

Warnings in Page : @t6g_mb_lib.t6g(sch_1):Page144
Signal HDD_ACTIVITY_BUF_N at (A 3) is labeled only once in the design.
Signal     NC_M2_0_NC1 at (B 2) is labeled only once in the design.
Signal M2_SSD0_CLKREQ_EN_N_BUF at (B 4) is labeled only once in the design.
Signal LED_HDD_ACTIVITY_N at (B 3) is labeled only once in the design.
Signal     NC_M2_0_NC5 at (B 2) is labeled only once in the design.
Signal     NC_M2_0_NC4 at (B 2) is labeled only once in the design.
Signal     NC_M2_0_NC3 at (B 2) is labeled only once in the design.
Signal RST_PERST_BUF_M2_0_N at (A 3) is labeled only once in the design.
Signal       NC_Q95_G2 at (A 3) is labeled only once in the design.
Signal       NC_Q95_D2 at (A 3) is labeled only once in the design.
Signal       NC_Q95_S2 at (A 3) is labeled only once in the design.
Signal HDD_ACTIVITY_BUF at (A 3) is labeled only once in the design.
Signal     NC_M2_0_NC6 at (B 2) is labeled only once in the design.
Signal     NC_M2_0_NC7 at (B 2) is labeled only once in the design.
Signal     NC_M2_0_NC9 at (B 2) is labeled only once in the design.
Signal    NC_M2_0_NC14 at (B 2) is labeled only once in the design.
Signal    NC_M2_0_NC15 at (B 2) is labeled only once in the design.
Signal    NC_M2_0_NC16 at (B 2) is labeled only once in the design.
Signal    NC_M2_0_NC17 at (B 2) is labeled only once in the design.
Signal    NC_M2_0_NC10 at (B 2) is labeled only once in the design.
Signal     NC_M2_0_NC2 at (B 2) is labeled only once in the design.
Signal FM_M2_SSD_0_PEDET at (B 3) is labeled only once in the design.
Signal    NC_M2_0_NC19 at (B 2) is labeled only once in the design.
Signal    NC_M2_0_NC18 at (B 2) is labeled only once in the design.
Signal   M2_0_PEWAKE_N at (B 4) is labeled only once in the design.
Signal  NC_M2_0_SUSCLK at (B 4) is labeled only once in the design.
Signal     NC_M2_0_NC8 at (B 2) is labeled only once in the design.
Signal    NC_M2_0_NC11 at (B 2) is labeled only once in the design.

Warnings in Page : @t6g_mb_lib.t6g(sch_1):Page145
Signal    TP_E1S_0_RFU at (B 4) is labeled only once in the design.
Signal    TP_E1S_0_MFG at (B 4) is labeled only once in the design.
Signal SMB_PCIE_E1S_ISO_EN_R2 at (A 3) is labeled only once in the design.
Signal RST_SMB_BUF_E1S_0_N at (A 3) is labeled only once in the design.
Signal   RST_SMB_E1S_N at (A 3) is labeled only once in the design.
Signal FM_LED_ACTIVE_E1S_0_R at (A 4) is labeled only once in the design.
Signal PU_E1S_0_DUALPORT_EN_N at (B 4) is labeled only once in the design.
Signal FM_LED_ACTIVE_E1S_0_R_BUF at (A 4) is labeled only once in the design.
Signal RST_PCIE_E1S_PERST_N at (B 4) is labeled only once in the design.
Signal TP_CLK_100M_E1S_0_DP at (B 2) is labeled only once in the design.
Signal TP_CLK_100M_E1S_0_DN at (B 2) is labeled only once in the design.

Warnings in Page : @t6g_mb_lib.t6g(sch_1):Page146
Signal P12V_E1S_0_EN_G at (B 4) is labeled only once in the design.
Signal  P12V_E1S_REG_0 at (B 3) is labeled only once in the design.
Signal   P12V_E1S_CB_0 at (B 3) is labeled only once in the design.
Signal   P12V_E1S_OV_0 at (B 3) is labeled only once in the design.
Signal P12V_E1S_GATE_0 at (B 2) is labeled only once in the design.
Signal P12V_E1S_PWRGD_0 at (B 2) is labeled only once in the design.
Signal P12V_E1S_FAULT_0 at (B 2) is labeled only once in the design.
Signal P12V_E1S_SENSE_0 at (B 2) is labeled only once in the design.
Signal   P3V3_E1S_OV_0 at (A 3) is labeled only once in the design.
Signal P3V3_E1S_GATE_0 at (A 2) is labeled only once in the design.
Signal   P3V3_E1S_UV_0 at (A 3) is labeled only once in the design.
Signal   P3V3_E1S_CB_0 at (A 3) is labeled only once in the design.
Signal P3V3_E1S_PWRGD_0 at (A 2) is labeled only once in the design.
Signal P3V3_E1S_FAULT_0 at (A 2) is labeled only once in the design.
Signal P3V3_E1S_SENSE_0 at (A 2) is labeled only once in the design.
Signal  P3V3_E1S_REG_0 at (A 3) is labeled only once in the design.
Signal P12V_E1S_UV_0_R at (B 4) is labeled only once in the design.
Signal  P3V3_E1S_VCC_0 at (A 3) is labeled only once in the design.
Signal P3V3_E1S_UV_0_R at (A 4) is labeled only once in the design.
Signal P3V3_E1S_0_EN_G at (A 4) is labeled only once in the design.
Signal P3V3_E1S_EN_0_R at (A 4) is labeled only once in the design.
Signal   P12V_E1S_UV_0 at (B 3) is labeled only once in the design.
Signal  P12V_E1S_VCC_0 at (B 3) is labeled only once in the design.
Signal P12V_E1S_EN_0_R at (B 4) is labeled only once in the design.

Warnings in Page : @t6g_mb_lib.t6g(sch_1):Page147
Signal P12V_E1S_ISET_0_R at (B 3) is labeled only once in the design.
Signal   P12V_E1S_SS_0 at (B 3) is labeled only once in the design.
Signal P12V_E1S_ISET_0 at (B 3) is labeled only once in the design.
Signal P3V3_E1S_EN_0_R2 at (A 2) is labeled only once in the design.
Signal P3V3_E1S_MODE_0 at (A 2) is labeled only once in the design.
Signal P3V3_E1S_ILIMIT_0 at (A 2) is labeled only once in the design.
Signal P3V3_E1S_DVDT_0 at (A 2) is labeled only once in the design.
Signal P3V3_E1S_PWRGD_0_R1 at (A 4) is labeled only once in the design.
Signal P3V3_E1S_GATE_0_PU293 at (A 1) is labeled only once in the design.
Signal P12V_E1S_OV_FB_0 at (B 3) is labeled only once in the design.
Signal P12V_E1S_FLTB_0 at (B 3) is labeled only once in the design.
Signal P12V_E1S_IMON_0 at (B 3) is labeled only once in the design.
Signal P12V_E1S_EN_0_R2 at (B 3) is labeled only once in the design.
Signal P12V_E1S_TIMER_0 at (B 3) is labeled only once in the design.

Warnings in Page : @t6g_mb_lib.t6g(sch_1):Page148
Signal SMB_E1S_3V3AUX_ISO_SDA_R at (B 3) is labeled only once in the design.
Signal SMB_PCIE_M2_0_EN at (B 3) is labeled only once in the design.
Signal SMB_PCIE_E1S_ISO_EN_R at (B 4) is labeled only once in the design.
Signal SMB_E1S_3V3AUX_ISO_SCL_R at (B 3) is labeled only once in the design.
Signal SMB_M2_P1_1V8AUX_SDA_R at (B 3) is labeled only once in the design.
Signal SMB_M2_P1_1V8AUX_SCL_R at (B 3) is labeled only once in the design.

Warnings in Page : @t6g_mb_lib.t6g(sch_1):Page150
Signal FM_AC_PWR_BTN_N at (B 2) is labeled only once in the design.
Signal SGPIO_SCM_INTR_R1_N at (B 2) is labeled only once in the design.
Signal TP_SPI_2_PLD_IO0 at (B 2) is labeled only once in the design.
Signal TP_SPI_2_PLD_IO2 at (A 2) is labeled only once in the design.
Signal SGPIO_SCM_LD_R_<0> at (B 2) is labeled only once in the design.
Signal SGPIO_SCM_DI_R_<0> at (B 2) is labeled only once in the design.
Signal      TP_STBY_EN at (B 4) is labeled only once in the design.
Signal PWRGD_PS_PWROK_R at (B 4) is labeled only once in the design.
Signal PU_JTAG_DBP_BMC_PRDY_N at (A 4) is labeled only once in the design.
Signal FM_UARTSW_MSB_R at (A 4) is labeled only once in the design.
Signal SCM_SYS_PWRBTN_R_N at (A 4) is labeled only once in the design.
Signal        TP_CHASI at (A 4) is labeled only once in the design.
Signal FM_UARTSW_LSB_R at (A 4) is labeled only once in the design.
Signal SCM_ROT_CPU_RST_N at (A 4) is labeled only once in the design.
Signal  TP_PCIE_RXN[1] at (A 4) is labeled only once in the design.
Signal  TP_PCIE_RXP[1] at (A 4) is labeled only once in the design.
Signal     FW_RECOVERY at (B 4) is labeled only once in the design.
Signal FM_LPC_ESPI_SEL at (B 2) is labeled only once in the design.
Signal SGPIO_SCM_DO_R_<0> at (B 2) is labeled only once in the design.
Signal     TP_PECI_BMC at (B 2) is labeled only once in the design.
Signal   I3C_SCM_2_SCL at (B 4) is labeled only once in the design.
Signal TP_SPI_2_PLD_IO3 at (A 2) is labeled only once in the design.
Signal SMB_HOST_CLK_3V3AUX_SCL_R0 at (B 4) is labeled only once in the design.
Signal SMB_PCIE3_3V3AUX_SCL_R at (B 4) is labeled only once in the design.
Signal SMB_CPU0_CPU1_SEC_SDA_R at (B 4) is labeled only once in the design.
Signal SMB_CPU0_CPU1_SEC_SCL_R at (B 4) is labeled only once in the design.
Signal SMB_VR_3V3AUX_SDA_R0 at (B 4) is labeled only once in the design.
Signal SMB_OCP_V3_2_3V3AUX_SDA_R0 at (B 4) is labeled only once in the design.
Signal SMB_OCP_V3_2_3V3AUX_SCL_R0 at (B 4) is labeled only once in the design.
Signal SMB_VR_3V3AUX_SCL_R0 at (B 4) is labeled only once in the design.
Signal SMB_CPU0_CPU1_APML_SDA_R at (B 4) is labeled only once in the design.
Signal SMB_CPU0_CPU1_APML_SCL_R at (B 4) is labeled only once in the design.
Signal SMB_OCP_SFF_3V3AUX_SDA_R0 at (B 4) is labeled only once in the design.
Signal SMB_OCP_SFF_3V3AUX_SCL_R0 at (B 4) is labeled only once in the design.
Signal   I3C_SCM_0_SCL at (B 4) is labeled only once in the design.
Signal   I3C_SCM_0_SDA at (B 4) is labeled only once in the design.
Signal   I3C_SCM_1_SCL at (B 4) is labeled only once in the design.
Signal   I3C_SCM_1_SDA at (B 4) is labeled only once in the design.
Signal   I3C_SCM_3_SDA at (B 4) is labeled only once in the design.
Signal   I3C_SCM_2_SDA at (B 4) is labeled only once in the design.
Signal   I3C_SCM_3_SCL at (B 4) is labeled only once in the design.
Signal SMB_HOST_CLK_3V3AUX_SDA_R0 at (B 4) is labeled only once in the design.
Signal SMB_PCIE3_3V3AUX_SDA_R at (B 4) is labeled only once in the design.
Signal SMB_PMBUS_3V3AUX_SDA_R0 at (B 4) is labeled only once in the design.
Signal SMB_PMBUS_3V3AUX_SCL_R0 at (B 4) is labeled only once in the design.
Signal SMB_1_PLD_3V3AUX_SCL_R3 at (B 4) is labeled only once in the design.
Signal     TP_BEEP_LED at (A 2) is labeled only once in the design.
Signal  TP_PCIE_TXN[1] at (A 2) is labeled only once in the design.
Signal  TP_PCIE_TXP[1] at (A 2) is labeled only once in the design.
Signal SMB_PCIE2_3V3AUX_SCL_R0 at (B 4) is labeled only once in the design.
Signal SMB_PCIE2_3V3AUX_SDA_R0 at (B 4) is labeled only once in the design.
Signal SMB_1_PLD_3V3AUX_SDA_R3 at (B 4) is labeled only once in the design.
Signal  TP_PCIE_TXP[3] at (A 2) is labeled only once in the design.
Signal TP_SPI_2_PLD_IO1 at (A 2) is labeled only once in the design.
Signal UART_CPU0_SCM_LVC3_UART1_R1_TX at (B 2) is labeled only once in the design.
Signal        PRSNT0_N at (B 2) is labeled only once in the design.
Signal UART_CPU0_SCM_LVC3_UART1_RX at (B 2) is labeled only once in the design.
Signal        IRQ0_A56 at (A 4) is labeled only once in the design.
Signal RST_MB_STBY_R_N at (A 4) is labeled only once in the design.
Signal SCM_HDT_DBREQ_N at (A 4) is labeled only once in the design.
Signal FM_SOL_UART_CH_SEL_R at (B 2) is labeled only once in the design.
Signal TP_PVCCIO_PECI_BMC at (B 2) is labeled only once in the design.
Signal SGPIO_SCM_LD_R_<1> at (B 2) is labeled only once in the design.
Signal SGPIO_SCM_CLK_R_<0> at (B 2) is labeled only once in the design.
Signal SGPIO_SCM_DO_R_<1> at (B 2) is labeled only once in the design.
Signal TP_SPI_2_PLD_CS_N at (B 2) is labeled only once in the design.
Signal TP_SPI_2_PLD_CLK at (B 2) is labeled only once in the design.
Signal SGPIO_SCM_RESET_R_N at (B 2) is labeled only once in the design.
Signal SGPIO_SCM_DI_R_<1> at (B 2) is labeled only once in the design.
Signal SGPIO_SCM_CLK_R_<1> at (B 2) is labeled only once in the design.

Warnings in Page : @t6g_mb_lib.t6g(sch_1):Page151
Signal     UART_VCC_J8 at (A 1) is labeled only once in the design.
Signal SMB_HOST_CLK_3V3AUX_SCL_R1 at (B 3) is labeled only once in the design.
Signal SMB_HOST_CLK_3V3AUX_SDA_R1 at (B 3) is labeled only once in the design.

Warnings in Page : @t6g_mb_lib.t6g(sch_1):Page152
Signal P12V_SCM_FLTB_N at (A 2) is labeled only once in the design.
Signal   P12V_SCM_IMON at (A 2) is labeled only once in the design.
Signal  P12V_SCM_OV_FB at (A 2) is labeled only once in the design.
Signal HP_LVC3_SCM_HSC_PWRGD_R at (A 2) is labeled only once in the design.
Signal  P12V_SCM_EN_R2 at (A 3) is labeled only once in the design.
Signal     P12V_SCM_SS at (A 3) is labeled only once in the design.
Signal  P12V_SCM_TIMER at (A 3) is labeled only once in the design.
Signal   P12V_SCM_EN_R at (B 4) is labeled only once in the design.
Signal   P12V_SCM_EN_G at (B 4) is labeled only once in the design.
Signal    P12V_SCM_REG at (B 2) is labeled only once in the design.
Signal P12V_SCM_FAULT_N at (B 2) is labeled only once in the design.
Signal  P12V_SCM_PWRGD at (B 2) is labeled only once in the design.
Signal     P12V_SCM_UV at (B 2) is labeled only once in the design.
Signal     P12V_SCM_CB at (B 2) is labeled only once in the design.
Signal    P12V_SCM_VCC at (B 2) is labeled only once in the design.
Signal  P12V_SCM_SENSE at (B 2) is labeled only once in the design.
Signal     P12V_SCM_OV at (B 2) is labeled only once in the design.
Signal   P12V_SCM_GATE at (B 2) is labeled only once in the design.
Signal   P12V_SCM_UV_R at (B 3) is labeled only once in the design.
Signal FM_SCM_PRSNT1_R_N at (B 4) is labeled only once in the design.
Signal     P12V_SCM_EN at (B 4) is labeled only once in the design.
Signal P12V_SCM_ISET_R at (A 3) is labeled only once in the design.
Signal   P12V_SCM_ISET at (A 3) is labeled only once in the design.
Signal P12V_SCM_FAULT_R_N at (B 1) has too little display space.
Signal HP_LVC3_SCM_HSC_PWRGD at (B 1) has too little display space.

Warnings in Page : @t6g_mb_lib.t6g(sch_1):Page153
Signal ESPI_CPU0_ALERT_R1_N at (B 3) is labeled only once in the design.

Warnings in Page : @t6g_mb_lib.t6g(sch_1):Page155
Signal IRQ_LVC3_WAKE_N at (B 3) is labeled only once in the design.
Signal    IRQ_WAKE_R_N at (B 2) is labeled only once in the design.

Warnings in Page : @t6g_mb_lib.t6g(sch_1):Page159
Signal I3C_SPD_DDRAF_CPU1_BYPASS_SCL at (A 3) is labeled only once in the design.
Signal I3C_SPD_DDRAF_CPU1_LVC1_SDA at (B 2) is labeled only once in the design.
Signal I3C_SPD_DDRAF_CPU1_LVC1_SCL at (B 2) is labeled only once in the design.
Signal I3C_SPD_DDRGL_CPU0_BYPASS_SDA at (B 3) is labeled only once in the design.
Signal I3C_1_SPD_DDRGL_CPU1_SDA at (A 3) is labeled only once in the design.
Signal I3C_1_SPD_DDRGL_CPU1_SCL at (A 3) is labeled only once in the design.
Signal I3C_1_SPD_DDRGL_CPU0_SDA at (B 3) is labeled only once in the design.
Signal I3C_SPD_DDRAF_CPU0_BYPASS_SCL at (B 3) is labeled only once in the design.
Signal I3C_0_SPD_DDRAF_CPU0_SDA at (B 3) is labeled only once in the design.
Signal I3C_SPD_DDRGL_CPU1_BYPASS_SDA at (A 3) is labeled only once in the design.
Signal I3C_SPD_DDRGL_CPU1_BYPASS_SCL at (A 3) is labeled only once in the design.
Signal I3C_SPD_DDRGL_CPU0_BYPASS_SCL at (B 3) is labeled only once in the design.
Signal I3C_SPD_DDRAF_CPU1_BYPASS_SDA at (A 3) is labeled only once in the design.
Signal I3C_SPD_DDRGL_CPU1_LVC1_SDA at (A 2) is labeled only once in the design.
Signal I3C_1_SPD_DDRGL_CPU0_SCL at (B 3) is labeled only once in the design.
Signal I3C_0_SPD_DDRAF_CPU0_SCL at (B 3) is labeled only once in the design.
Signal I3C_SPD_DDRAF_CPU0_LVC1_SDA at (B 2) is labeled only once in the design.
Signal I3C_0_SPD_DDRAF_CPU1_SDA at (B 3) is labeled only once in the design.
Signal I3C_SPD_DDRGL_CPU0_LVC1_SCL at (B 2) is labeled only once in the design.
Signal I3C_SPD_DDRAF_CPU0_LVC1_SCL at (B 2) is labeled only once in the design.
Signal I3C_SPD_DDRGL_CPU1_LVC1_SCL at (A 2) is labeled only once in the design.
Signal I3C_SPD_DDRAF_CPU0_BYPASS_SDA at (B 3) is labeled only once in the design.
Signal I3C_SPD_DDRGL_CPU0_LVC1_SDA at (B 2) is labeled only once in the design.
Signal I3C_0_SPD_DDRAF_CPU1_SCL at (B 3) is labeled only once in the design.

Warnings in Page : @t6g_mb_lib.t6g(sch_1):Page160
Signal SMB_CPU0_CPU1_APML_BUF2_SDA at (B 4) is labeled only once in the design.
Signal SMB_CPU0_CPU1_APML_BUF1_SDA_R1 at (B 3) is labeled only once in the design.
Signal SMB_CPU0_CPU1_APML_BUF1_SCL_R1 at (B 3) is labeled only once in the design.
Signal SMB_CPU0_CPU1_APML_BUF2_SCL at (B 4) is labeled only once in the design.
Signal        PU_U5_EN at (B 3) is labeled only once in the design.
Signal       PU_U96_EN at (A 4) is labeled only once in the design.
Signal SMB_CPU0_CPU1_SEC_SCL_R1 at (A 3) is labeled only once in the design.
Signal SMB_CPU0_CPU1_SEC_SDA_R1 at (A 3) is labeled only once in the design.
Signal SMB_CPU0_CPU1_APML_BUF1_SDA at (B 4) is labeled only once in the design.
Signal SMB_CPU0_CPU1_APML_BUF1_SCL at (B 4) is labeled only once in the design.
Signal        PU_U2_EN at (B 4) is labeled only once in the design.
Signal SMB_CPU0_CPU1_APML_BUF2_SDA_R1 at (B 3) is labeled only once in the design.
Signal SMB_CPU0_CPU1_APML_BUF2_SCL_R1 at (B 3) is labeled only once in the design.

Warnings in Page : @t6g_mb_lib.t6g(sch_1):Page161
Signal SMB_APML_CPU1_MUX2_SDA at (B 2) is labeled only once in the design.
Signal SMB_APML_CPU1_MUX2_SCL at (B 2) is labeled only once in the design.
Signal SMB_APML_CPU0_MUX2_SDA at (B 2) is labeled only once in the design.
Signal SMB_CPU0_CPU1_APML_MUX2_SCL at (B 3) is labeled only once in the design.
Signal SMB_CPU0_CPU1_APML_MUX1_SCL at (B 4) is labeled only once in the design.
Signal SMB_CPU0_CPU1_APML_MUX1_SDA at (B 4) is labeled only once in the design.
Signal SMB_APML_CPU0_R_SDA at (B 3) is labeled only once in the design.
Signal SMB_APML_CPU1_R_SDA at (B 3) is labeled only once in the design.
Signal SMB_APML_CPU1_R_SCL at (B 3) is labeled only once in the design.
Signal SMB_APML_CPU0_R_SCL at (B 3) is labeled only once in the design.
Signal SMB_CPU1_SEC_R_SDA at (A 3) is labeled only once in the design.
Signal SMB_CPU1_SEC_R_SCL at (A 3) is labeled only once in the design.
Signal SMB_CPU0_SEC_R_SDA at (A 3) is labeled only once in the design.
Signal SMB_CPU0_SEC_R_SCL at (A 3) is labeled only once in the design.
Signal I3C_MUX_CPU0_VIO at (B 4) is labeled only once in the design.
Signal SMB_CPU0_CPU1_APML_MUX2_SDA at (B 3) is labeled only once in the design.
Signal SMB_APML_CPU0_MUX2_SCL at (B 2) is labeled only once in the design.

Warnings in Page : @t6g_mb_lib.t6g(sch_1):Page164
Signal    UART_VCC_J13 at (A 2) is labeled only once in the design.
Signal UART_CPU0_LVC3_UART0_R_TX at (B 3) is labeled only once in the design.
Signal UART_CPU0_SCM_LVC3_UART1_R_TX at (B 3) is labeled only once in the design.
Signal UART_CPU0_UART0_R_RX at (B 3) is labeled only once in the design.
Signal UART_CPU0_SCM_UART1_R_RX at (B 3) is labeled only once in the design.
Signal  UART_LS_EN_R_N at (A 4) is labeled only once in the design.
Signal UART_CPU0_LVC3_UART0_RX at (A 2) has too little display space.

Warnings in Page : @t6g_mb_lib.t6g(sch_1):Page165
Signal LED_BIOS_DBG_MODE_N at (A 2) is labeled only once in the design.
Signal LED_BIOS_DBG_MODE at (A 3) is labeled only once in the design.
Signal LED_BIOS_DBG_MODE_R at (A 3) is labeled only once in the design.

Warnings in Page : @t6g_mb_lib.t6g(sch_1):Page166
Signal FM_SMERR_BUF_LED_N at (B 4) is labeled only once in the design.
Signal BOOT_RDY_BUF_LED at (B 3) is labeled only once in the design.
Signal BOOT_RDY_BUF_R_LED at (B 3) is labeled only once in the design.
Signal   BOOT_RDY_R1_N at (B 4) is labeled only once in the design.
Signal    BOOT_RDY_LED at (B 3) is labeled only once in the design.
Signal PU_BOOT_RDY_LED at (B 2) is labeled only once in the design.
Signal  BOOT_RDY_LED_N at (B 2) is labeled only once in the design.
Signal P5V_STBY_PWR_LED at (A 2) is labeled only once in the design.
Signal     SMERR_LED_N at (B 2) is labeled only once in the design.
Signal       SMERR_LED at (B 3) is labeled only once in the design.
Signal    PU_SMERR_LED at (B 2) is labeled only once in the design.
Signal PU_P12V_ALL_PWROK_LED at (A 2) is labeled only once in the design.
Signal P12V_ALL_PWROK_N at (A 3) is labeled only once in the design.
Signal FM_SMERR_BUF_R_LED_N at (B 3) is labeled only once in the design.

Warnings in Page : @t6g_mb_lib.t6g(sch_1):Page167
Signal PD_BIOS_DEBUG_MODE at (A 4) is labeled only once in the design.
Signal        U124_VCC at (A 3) is labeled only once in the design.

Warnings in Page : @t6g_mb_lib.t6g(sch_1):Page169
Signal P3V3_AUX_DSC_G2 at (A 3) is labeled only once in the design.
Signal P12V_AUX_DSC_VOL at (B 4) is labeled only once in the design.
Signal    P12V_AUX_DSC at (B 2) is labeled only once in the design.
Signal P3V3_AUX_DSC_VOL at (A 4) is labeled only once in the design.
Signal P3V3_AUX_DSC_G1 at (B 4) is labeled only once in the design.
Signal    P3V3_AUX_DSC at (B 2) is labeled only once in the design.
Signal P12V_AUX_DSC_S1 at (B 4) is labeled only once in the design.
Signal P12V_AUX_DSC_G1 at (B 4) is labeled only once in the design.
Signal P12V_AUX_DSC_G2 at (B 3) is labeled only once in the design.
Signal P3V3_AUX_DSC_S1 at (A 3) is labeled only once in the design.

Warnings in Page : @t6g_mb_lib.t6g(sch_1):Page171
Signal    PU_U160_EN_N at (B 3) is labeled only once in the design.
Signal    PU_U212_EN_N at (A 3) is labeled only once in the design.
Signal    PD_U212_EN_N at (A 3) is labeled only once in the design.
Signal SCM_JTAG_MUX_S0_R2 at (A 3) is labeled only once in the design.
Signal       U212_EN_N at (A 3) is labeled only once in the design.
Signal    PD_U160_EN_N at (B 3) is labeled only once in the design.
Signal TP_JTAG_SCM_SLOT3_R_TMS at (B 2) is labeled only once in the design.
Signal JTAG_SCM_PLD_R_TDO at (A 3) is labeled only once in the design.
Signal JTAG_SCM_PLD_R_TCK at (B 3) is labeled only once in the design.
Signal TP_JTAG_SCM_SLOT3_R_TCK at (B 2) is labeled only once in the design.
Signal JTAG_SCM_PLD_R_TMS at (B 3) is labeled only once in the design.
Signal       U160_EN_N at (B 3) is labeled only once in the design.
Signal SCM_JTAG_MUX_S0_R1 at (B 3) is labeled only once in the design.
Signal JTAG_SCM_MUX_R_TMS at (B 3) is labeled only once in the design.
Signal JTAG_SCM_MUX_R_TCK at (B 3) is labeled only once in the design.
Signal TP_JTAG_SCM_SLOT3_R_TDO at (A 2) is labeled only once in the design.
Signal JTAG_SCM_MUX_R_TDO at (A 3) is labeled only once in the design.
Signal JTAG_SCM_PLD_R_TDI at (A 3) is labeled only once in the design.
Signal JTAG_SCM_MUX_R_TDI at (A 3) is labeled only once in the design.
Signal TP_JTAG_SCM_SLOT3_R_TDI at (A 2) is labeled only once in the design.

Warnings in Page : @t6g_mb_lib.t6g(sch_1):Page172
Signal HDT_HDR_TRST_N_R at (B 3) is labeled only once in the design.
Signal HDT_CPU0_HDT_CONN_TESTEN at (B 3) is labeled only once in the design.
Signal HDT_HDR_DBREQ_R_N at (B 3) is labeled only once in the design.
Signal  JTAG_DBREQ_R_N at (B 2) is labeled only once in the design.
Signal      JTAG_TCK_R at (B 2) is labeled only once in the design.
Signal   JTAG_TRST_R_N at (B 2) is labeled only once in the design.
Signal      JTAG_TMS_R at (B 2) is labeled only once in the design.
Signal     JTAG_TDO_R1 at (B 4) is labeled only once in the design.
Signal      JTAG_TDI_R at (B 4) is labeled only once in the design.
Signal   HDT_HDR_R_TDI at (B 3) is labeled only once in the design.
Signal   HDT_HDR_R_TMS at (B 3) is labeled only once in the design.
Signal   HDT_HDR_R_TCK at (B 3) is labeled only once in the design.
Signal   HDT_HDR_TDO_R at (B 4) is labeled only once in the design.
Signal HDT_CPU0_XTRIG_L7 at (B 3) is labeled only once in the design.
Signal HDT_CPU0_XTRIG_L6 at (B 3) is labeled only once in the design.
Signal HDT_CPU0_XTRIG_L5 at (B 3) is labeled only once in the design.
Signal   PRSNT_HDT_R_N at (B 4) is labeled only once in the design.
Signal JTAG_BMC_R_D_OE at (B 4) is labeled only once in the design.
Signal   JTAG_BMC_OE_N at (A 4) is labeled only once in the design.

Warnings in Page : @t6g_mb_lib.t6g(sch_1):Page173
Signal JTAG_P1_R_DBREQ_N at (B 3) is labeled only once in the design.
Signal JTAG_P0_R_DBREQ_N at (B 3) is labeled only once in the design.
Signal JTAG_P1_R_TRST_N at (B 3) is labeled only once in the design.
Signal   JTAG_P1_R_TMS at (B 3) is labeled only once in the design.
Signal   JTAG_P1_R_TCK at (B 3) is labeled only once in the design.
Signal   JTAG_P0_R_TCK at (B 3) is labeled only once in the design.
Signal JTAG_P0_R_TRST_N at (B 3) is labeled only once in the design.
Signal   JTAG_P0_R_TMS at (B 3) is labeled only once in the design.
Signal      JTAG_TDO_R at (A 4) is labeled only once in the design.
Signal JTAG_CPUX_TDI_R1 at (A 3) is labeled only once in the design.
Signal       U152_OE_N at (A 4) is labeled only once in the design.

Warnings in Page : @t6g_mb_lib.t6g(sch_1):Page174
Signal FM_PLD_CPU0_PRSNT_HDT_N at (B 4) is labeled only once in the design.
Signal FM_PLD_CPU1_PRSNT_HDT_N at (B 2) is labeled only once in the design.
Signal JTAG_CPU1_BYPASS at (B 2) is labeled only once in the design.
Signal JTAG_CPU0_TDO_CPU1_TDI at (B 3) is labeled only once in the design.
Signal JTAG_CPU0_BYPASS at (B 3) is labeled only once in the design.
Signal JTAG_CPUX_TDO_R at (B 1) is labeled only once in the design.
Signal JTAG_CPU0_BYPASS_R1 at (B 3) is labeled only once in the design.
Signal JTAG_CPU0_TDO_CPU1_TDI_R1 at (B 3) is labeled only once in the design.
Signal JTAG_CPU0_R_TDI at (B 3) is labeled only once in the design.
Signal JTAG_CPU1_R_TDI at (B 2) is labeled only once in the design.

Warnings in Page : @t6g_mb_lib.t6g(sch_1):Page176
Signal SMB_USB_CPU0_HUB1_SCL_R2 at (B 2) is labeled only once in the design.
Signal SMB_USB_CPU0_HUB1_SDA_R2 at (B 2) is labeled only once in the design.
Signal  PD_USB_CPU0_WP at (B 2) is labeled only once in the design.
Signal USB_CPU0_ADD_A1 at (B 1) is labeled only once in the design.
Signal USB_CPU0_ADD_A0 at (B 1) is labeled only once in the design.
Signal PU_CPU0_USB_HUB_PWR_EN at (B 4) is labeled only once in the design.
Signal PU_CPU0_USB_HUB_OVRCURR at (B 4) is labeled only once in the design.
Signal XTAL_USB_CPU0_HUB1_XIN at (A 4) is labeled only once in the design.
Signal PU_CPU0_USB_HUB_RESERVED2 at (B 4) is labeled only once in the design.
Signal PU_CPU0_USB_HUB_RESERVED1 at (B 4) is labeled only once in the design.
Signal USB_CPU0_HUB1_RREF_USB2 at (B 4) is labeled only once in the design.
Signal USB_CPU0_HUB1_RREF_SS at (B 4) is labeled only once in the design.
Signal USB_CPU0_HUB1_VBUS_US at (B 4) is labeled only once in the design.
Signal TP_CPU0_USB_HUB1_SUSPEND at (B 4) is labeled only once in the design.
Signal XTAL_USB_CPU0_HUB1_XOUT at (A 4) is labeled only once in the design.
Signal RST_USB_CPU0_HUB1_R_N at (A 4) is labeled only once in the design.
Signal USB_CPU0_HUB1_VBUS_DS at (B 2) is labeled only once in the design.
Signal USB_CPU0_ADD_A2 at (B 1) is labeled only once in the design.
Signal USB_CPU0_HUB1_MODE_SEL1 at (A 3) is labeled only once in the design.
Signal USB_CPU0_HUB1_MODE_SEL0 at (A 3) is labeled only once in the design.
Signal SMB_USB_CPU0_HUB1_SCL at (B 3) has too little display space.

Warnings in Page : @t6g_mb_lib.t6g(sch_1):Page178
Signal USB_HUB2_TI_USB_SSRXM_DN4_MRP_VDD12 at (A 2) is labeled only once in the design.
Signal USB_HUB2_TI_USB_DM_DN3_MRP_VDD33 at (B 2) is labeled only once in the design.
Signal USB_HUB2_TI_TEST_MRP_PROG_FUNC6 at (A 4) is labeled only once in the design.
Signal USB_HUB2_TI_TEST at (A 4) is labeled only once in the design.
Signal USB_HUB2_MRP_PROG_FUNC6 at (A 4) is labeled only once in the design.
Signal USB_HUB2_MRP_I2C_SLV_CFG1 at (A 4) is labeled only once in the design.
Signal USB_HUB2_TI_PWRCTL3_MRP_VDD33 at (B 4) is labeled only once in the design.
Signal USB_HUB2_TI_PWRCTL2_MRP_VDD12 at (B 4) is labeled only once in the design.
Signal USB_HUB2_TI_OVERCCUR4 at (A 4) is labeled only once in the design.
Signal USB_HUB2_TI_OVERCUR4_MRP_I2C_SLV_CFG1 at (A 4) is labeled only once in the design.
Signal USB_HUB2_MRP_CFG_BC_EN at (A 4) is labeled only once in the design.
Signal USB_HUB2_TI_OVERCUR3 at (A 4) is labeled only once in the design.
Signal USB_HUB2_TI_OVERCUR1_MRP_PROG_FUNC4 at (B 4) is labeled only once in the design.
Signal USB_HUB2_TI_OVERCUR2 at (B 4) is labeled only once in the design.
Signal USB_HUB2_TI_PWRCTL_POL_MRP_VBUS_DET at (B 4) is labeled only once in the design.
Signal USB_HUB2_MRP_VBUS_DET at (B 4) is labeled only once in the design.
Signal USB_HUB2_TI_USB_VBUS at (B 4) is labeled only once in the design.
Signal USB_HUB2_MRP_RESET_N at (B 4) is labeled only once in the design.
Signal USB_HUB2_TI_PWRCTL_POL at (B 4) is labeled only once in the design.
Signal USB_HUB2_TI_GRSTZ_MRP_PROG_FUNC1 at (B 4) is labeled only once in the design.
Signal USB_HUB2_TI_OVERCUR1 at (B 4) is labeled only once in the design.
Signal USB_HUB2_TI_OVERCUR2_MRP_PROG_FUNC5 at (B 4) is labeled only once in the design.
Signal USB_HUB2_TI_OVERCUR3_MRP_CFG_BC_EN at (A 4) is labeled only once in the design.
Signal USB_HUB2_TI_USB_DP_DN1_MRP_CFG_STRAP at (B 2) is labeled only once in the design.
Signal USB_HUB2_TI_USB_SSRXP_DN1_MRP_VDD12 at (B 2) is labeled only once in the design.
Signal USB_HUB2_MRP_CFG_STRAP at (B 1) is labeled only once in the design.
Signal USB_HUB2_TI_USB_SSRXM_DN3_MRP_VDD12 at (B 2) is labeled only once in the design.
Signal USB_HUB2_TI_USB_DP_DN3_MRP_VDD12 at (B 2) is labeled only once in the design.
Signal USB_HUB2_TI_USB_R1_MRP_RBIAS at (A 2) is labeled only once in the design.
Signal USB_HUB2_TI_USB_VBUS_MRP_RESET_N at (B 4) is labeled only once in the design.

Warnings in Page : @t6g_mb_lib.t6g(sch_1):Page179
Signal USB_HUB2_MRP_I2C_SLV_CFG0 at (A 2) is labeled only once in the design.
Signal USB_HUB2_TI_GANGED at (B 2) is labeled only once in the design.
Signal USB_HUB2_TI_HS_SUSPEND_MRP_CFG_NON_REM at (B 4) is labeled only once in the design.
Signal SMB_USB_HUB2_TI_SCL_MRP_PRT_CTL1 at (B 4) is labeled only once in the design.
Signal SMB_USB_HUB2_TI_SDA_MRP_PRT_CTL2 at (B 4) is labeled only once in the design.
Signal USB_HUB2_MRP_PRT_CTL4_GANGPWR at (B 1) is labeled only once in the design.
Signal USB_HUB2_TI_VDD33_MRP_PROG_FUNC7 at (B 2) is labeled only once in the design.
Signal USB_HUB2_TI_VDD_MRP_USB3DN_TXDP3 at (B 2) is labeled only once in the design.
Signal USB_HUB2_TI_FULLPWRMGMTZ_MRP_PROG_FUNC3 at (B 4) is labeled only once in the design.
Signal USB_HUB2_TI_HS_SUSPEND at (B 4) is labeled only once in the design.
Signal USB_HUB2_TI_VDD_MRP_USB3DN_TXDM1 at (B 2) is labeled only once in the design.
Signal USB_HUB2_TI_VDD_MRP_USB3DN_RXDM1 at (B 2) is labeled only once in the design.
Signal USB_HUB2_TI_VDD_MRP_USB3DN_TXDP4 at (B 2) is labeled only once in the design.
Signal USB_HUB2_TI_VDD_MRP_USB3DN_RXDP4 at (B 2) is labeled only once in the design.
Signal USB_HUB2_TI_VDD33_MRP_PRT_CTL4_GANGPWR at (B 2) is labeled only once in the design.
Signal USB_HUB2_TI_SMBUSZ_MRP_PROG_FUNC2 at (B 4) is labeled only once in the design.
Signal USB_HUB2_MRP_CFG_NON_REM at (B 4) is labeled only once in the design.
Signal XTAL_USB_CPU0_HUB2_XOUT at (B 4) is labeled only once in the design.
Signal XTAL_USB_CPU0_HUB2_XIN at (B 4) is labeled only once in the design.

Warnings in Page : @t6g_mb_lib.t6g(sch_1):Page182
Signal FM_9ZXL045_P0_DEV_EN at (B 4) is labeled only once in the design.
Signal     NC_U314_NC2 at (B 4) is labeled only once in the design.
Signal     NC_U314_NC3 at (B 4) is labeled only once in the design.
Signal     NC_U314_NC0 at (B 4) is labeled only once in the design.
Signal     NC_U314_NC1 at (B 4) is labeled only once in the design.
Signal FM_9ZXL045_P0_0_OE_N at (B 2) is labeled only once in the design.
Signal NC_U314_FBOUT_N at (B 4) is labeled only once in the design.
Signal   NC_U314_FBOUT at (B 4) is labeled only once in the design.
Signal P3V3_9ZXL045_P0 at (B 4) is labeled only once in the design.
Signal FM_9ZXL045_P0_1_OE_N at (B 2) is labeled only once in the design.
Signal FM_9ZXL045_P0_2_OE_N at (B 2) is labeled only once in the design.
Signal FM_9ZXL045_P0_3_OE_N at (B 2) is labeled only once in the design.

Warnings in Page : @t6g_mb_lib.t6g(sch_1):Page183
Signal  NC_U10_FBOUT_N at (B 4) is labeled only once in the design.
Signal      NC_U10_NC0 at (B 4) is labeled only once in the design.
Signal    NC_U10_FBOUT at (B 4) is labeled only once in the design.
Signal      NC_U10_NC1 at (B 4) is labeled only once in the design.
Signal P3V3_9ZXL045_P1 at (B 4) is labeled only once in the design.
Signal FM_9ZXL045_P1_0_OE_N at (B 2) is labeled only once in the design.
Signal FM_9ZXL045_P1_1_OE_N at (B 2) is labeled only once in the design.
Signal      NC_U10_NC3 at (B 4) is labeled only once in the design.
Signal      NC_U10_NC2 at (B 4) is labeled only once in the design.
Signal FM_9ZXL045_P1_2_OE_N at (B 2) is labeled only once in the design.
Signal FM_9ZXL045_P1_3_OE_N at (B 2) is labeled only once in the design.
Signal FM_9ZXL045_P1_DEV_EN at (B 4) is labeled only once in the design.

Warnings in Page : @t6g_mb_lib.t6g(sch_1):Page184
Signal SMB_RT_CPU0_P2_SCL at (B 3) is labeled only once in the design.
Signal SMB_RT_CPU0_P2_SDA at (B 3) is labeled only once in the design.
Signal SMB_RT_CPU1_P0_SDA at (B 4) is labeled only once in the design.
Signal SMB_RT_CPU0_P3_SDA at (B 3) is labeled only once in the design.
Signal SMB_RT_CPU1_P2_SDA at (B 4) is labeled only once in the design.
Signal SMB_RT_CPU1_P3_SCL at (B 4) is labeled only once in the design.
Signal SMB_RT_CPU1_P2_SCL at (B 4) is labeled only once in the design.
Signal SMB_RT_CPU1_P3_SDA at (B 4) is labeled only once in the design.
Signal SMB_RT_CPU1_P1_SCL at (B 4) is labeled only once in the design.
Signal SMB_RT_CPU1_P1_SDA at (B 4) is labeled only once in the design.
Signal SMB_RT_CPU1_P0_SCL at (B 4) is labeled only once in the design.
Signal    RST_SMB_RT_N at (B 4) is labeled only once in the design.
Signal SMB_RT_CPU0_P3_SCL at (B 3) is labeled only once in the design.
Signal SMB_RT_CPU0_P1_SDA at (B 3) is labeled only once in the design.
Signal SMB_MUX_RT_R2_SDA at (B 1) is labeled only once in the design.
Signal SMB_MUX_RT_R2_SCL at (B 1) is labeled only once in the design.
Signal SMB_RT_CPU0_P1_SCL at (B 3) is labeled only once in the design.
Signal SMB_RT_CPU0_P0_SCL at (B 3) is labeled only once in the design.
Signal SMB_RT_CPU0_P0_SDA at (B 3) is labeled only once in the design.
Signal  SMB_MUX_RT_SDA at (B 3) is labeled only once in the design.
Signal  SMB_MUX_RT_SCL at (B 3) is labeled only once in the design.

Warnings in Page : @t6g_mb_lib.t6g(sch_1):Page185
Signal SMB_MUX_RT_ROM_SDA at (B 3) is labeled only once in the design.
Signal SMB_MUX_RT_ROM_SCL at (B 3) is labeled only once in the design.
Signal RST_SMB_RT_ROM_N at (B 4) is labeled only once in the design.
Signal SMB_RT_CPU1_P0_ROM_MUX_2D_R_SDA at (B 4) has too little display space.
Signal SMB_RT_CPU1_P0_ROM_MUX_2D_R_SCL at (B 4) has too little display space.
Signal SMB_RT_CPU1_P1_ROM_MUX_2D_R_SDA at (B 4) has too little display space.
Signal SMB_RT_CPU1_P3_ROM_MUX_2D_R_SCL at (B 4) has too little display space.
Signal SMB_RT_CPU1_P3_ROM_MUX_2D_R_SDA at (B 4) has too little display space.
Signal SMB_RT_CPU1_P2_ROM_MUX_2D_R_SCL at (B 4) has too little display space.
Signal SMB_RT_CPU1_P2_ROM_MUX_2D_R_SDA at (B 4) has too little display space.
Signal SMB_RT_CPU1_P1_ROM_MUX_2D_R_SCL at (B 4) has too little display space.

Warnings in Page : @t6g_mb_lib.t6g(sch_1):Page186
Signal RT_ROM_MUX8_OE_N at (A 2) is labeled only once in the design.
Signal FM_SMB_RT_ROM_MUX8_SEL at (A 2) is labeled only once in the design.
Signal FM_SMB_RT_ROM_MUX7_SEL at (A 2) is labeled only once in the design.
Signal RT_ROM_MUX7_OE_N at (A 2) is labeled only once in the design.
Signal FM_SMB_RT_ROM_MUX6_SEL at (B 2) is labeled only once in the design.
Signal RT_ROM_MUX6_OE_N at (B 2) is labeled only once in the design.
Signal FM_SMB_RT_ROM_MUX1_SEL at (B 4) is labeled only once in the design.
Signal RT_ROM_MUX1_OE_N at (B 4) is labeled only once in the design.
Signal RT_ROM_MUX2_OE_N at (B 4) is labeled only once in the design.
Signal FM_SMB_RT_ROM_MUX3_SEL at (B 4) is labeled only once in the design.
Signal RT_ROM_MUX3_OE_N at (B 4) is labeled only once in the design.
Signal RT_ROM_MUX4_OE_N at (A 4) is labeled only once in the design.
Signal FM_SMB_RT_ROM_MUX4_SEL at (A 4) is labeled only once in the design.
Signal RT_ROM_MUX5_OE_N at (B 2) is labeled only once in the design.
Signal FM_SMB_RT_ROM_MUX5_SEL at (B 2) is labeled only once in the design.
Signal FM_SMB_RT_ROM_MUX2_SEL at (B 4) is labeled only once in the design.

Warnings in Page : @t6g_mb_lib.t6g(sch_1):Page187
Signal     P3V3_STBY_R at (B 4) is labeled only once in the design.
Signal  P3V3_RTC_AUX_R at (B 3) is labeled only once in the design.
Signal  P1V5_BAT_OUT_R at (B 2) is labeled only once in the design.
Signal      CLR_CMOS_N at (B 2) is labeled only once in the design.
Signal           U9_NR at (A 2) is labeled only once in the design.
Signal       P3V_BAT_R at (B 4) is labeled only once in the design.
Signal         P3V_BAT at (B 4) is labeled only once in the design.

Warnings in Page : @t6g_mb_lib.t6g(sch_1):Page188
Signal     PWRGD_P5V_R at (A 3) is labeled only once in the design.
Signal   PWRGD_P3V3_R1 at (A 3) is labeled only once in the design.
Signal PWRGD_P3V3_EN_N at (A 4) is labeled only once in the design.
Signal PWRGD_P3V3_EN_R at (A 4) is labeled only once in the design.
Signal   PWRGD_P3V3_EN at (A 4) is labeled only once in the design.
Signal   VR_P5V_EN_D_R at (B 4) is labeled only once in the design.
Signal     PWRGD_P5V_N at (A 1) is labeled only once in the design.
Signal    PWRGD_P5V_R1 at (A 2) is labeled only once in the design.
Signal       VR_P5V_EN at (B 4) is labeled only once in the design.
Signal  VR_P5V_EN_D_R1 at (B 3) is labeled only once in the design.
Signal    SW_P3V3_EN_N at (B 2) is labeled only once in the design.
Signal SW_P3V3_EN_ISO_R at (B 2) is labeled only once in the design.
Signal    SW_P3V3_EN_R at (A 2) is labeled only once in the design.
Signal   PWRGD_P5V_R_N at (A 2) is labeled only once in the design.
Signal  SW_P3V3_EN_ISO at (B 1) is labeled only once in the design.
Signal     VR_P5V_EN_D at (B 2) is labeled only once in the design.

Warnings in Page : @t6g_mb_lib.t6g(sch_1):Page189
Signal     P5V_AUX_REF at (B 3) is labeled only once in the design.
Signal    P5V_AUX_MODE at (B 4) is labeled only once in the design.
Signal      P5V_AUX_EN at (B 4) is labeled only once in the design.
Signal PWRGD_P5V_AUX_R at (B 3) is labeled only once in the design.
Signal  SW_P5V_AUX_BST at (B 3) is labeled only once in the design.
Signal      P5V_AUX_CS at (B 4) is labeled only once in the design.
Signal      P5V_AUX_FB at (B 3) is labeled only once in the design.
Signal   SW_P5V_AUX_SW at (B 3) is labeled only once in the design.
Signal  SW_P5V_AUX_FLT at (B 4) is labeled only once in the design.
Signal   P5V_AUX_VCC\G at (B 3) is labeled only once in the design.

Warnings in Page : @t6g_mb_lib.t6g(sch_1):Page190
Signal  SW_P3V3_AUX_SW at (B 3) is labeled only once in the design.
Signal SW_P3V3_AUX_BOOTR at (B 3) is labeled only once in the design.
Signal SW_P3V3_AUX_FLT at (B 4) is labeled only once in the design.
Signal   P3V3_AUX_MODE at (B 3) is labeled only once in the design.
Signal   P3V3_AUX_ILIM at (A 3) is labeled only once in the design.
Signal        NC_PU9_4 at (B 3) is labeled only once in the design.
Signal     P3V3_AUX_SS at (A 3) is labeled only once in the design.
Signal        NC_PU9_3 at (B 3) is labeled only once in the design.
Signal        NC_PU9_1 at (A 3) is labeled only once in the design.
Signal        NC_PU9_2 at (A 3) is labeled only once in the design.
Signal PWRGD_P3V3_AUX_R1 at (B 3) is labeled only once in the design.
Signal SW_P3V3_AUX_BOOT at (B 3) is labeled only once in the design.
Signal SW_P3V3_AUX_BOOT_R at (B 2) is labeled only once in the design.
Signal    P3V3_AUX_VOS at (A 3) is labeled only once in the design.
Signal       NC_HICCUP at (B 3) is labeled only once in the design.
Signal     P3V3_AUX_FB at (B 3) is labeled only once in the design.
Signal   P3V3_AUX_VDRV at (B 3) is labeled only once in the design.
Signal    P3V3_AUX_VCC at (B 3) is labeled only once in the design.
Signal     P3V3_AUX_EN at (B 3) is labeled only once in the design.

Warnings in Page : @t6g_mb_lib.t6g(sch_1):Page192
Signal SW_PVDD_33_S5_SW at (B 3) is labeled only once in the design.
Signal SW_PVDD_33_S5_BST at (B 3) is labeled only once in the design.
Signal PWRGD_PVDD33_S5 at (B 3) is labeled only once in the design.
Signal PVDD_33_S5_MODE at (B 4) is labeled only once in the design.
Signal   PVDD_33_S5_CS at (A 4) is labeled only once in the design.
Signal  PVDD_33_S5_REF at (A 3) is labeled only once in the design.
Signal   PVDD_33_S5_FB at (B 3) is labeled only once in the design.
Signal SW_P12V_AUX_PVDD_33_S5_FLT at (B 4) is labeled only once in the design.
Signal SW_PVDD_33_S5_BST_R at (B 2) is labeled only once in the design.

Warnings in Page : @t6g_mb_lib.t6g(sch_1):Page193
Signal PVDDCR_CPU0_P0_VCC at (B 2) is labeled only once in the design.
Signal PVDDCR_SOC_P0_EN_GD at (A 4) is labeled only once in the design.
Signal PVDDCR_SOC_P0_EN_RC at (A 4) is labeled only once in the design.
Signal PWRGD_PVDDCR_SOC_P0_R at (A 3) is labeled only once in the design.
Signal PVDDCR_CPU0_P0_OCP_N_R at (A 3) is labeled only once in the design.
Signal SVID_PVDDCR_CPU0_P0_SVTI at (B 4) is labeled only once in the design.
Signal SVID_PVDDCR_CPU0_P0_SVTI_R at (B 3) is labeled only once in the design.
Signal PVDDCR_CPU0_P0_PMSCL_R at (B 3) is labeled only once in the design.
Signal SVID_PVDDCR_CPU0_P0_SVC_R1 at (B 3) is labeled only once in the design.
Signal SVID_PVDDCR_CPU0_P0_SVTO_R at (B 3) is labeled only once in the design.
Signal PVDDCR_CPU0_P0_RESET_N_R at (A 3) is labeled only once in the design.
Signal NC_PVDDCR_CPU0_P0_IMON7 at (B 2) is labeled only once in the design.
Signal NC_PVDDCR_CPU0_P0_IMON8 at (B 2) is labeled only once in the design.
Signal SVID_PVDDCR_CPU0_P0_SVD_R1 at (B 3) is labeled only once in the design.
Signal PVDDCR_CPU0_P0_PMALERT_R at (B 3) is labeled only once in the design.
Signal PVDDCR_CPU0_P0_EN_R at (B 3) is labeled only once in the design.
Signal PVDDCR_CPU0_P0_PMSDA_R at (B 3) is labeled only once in the design.
Signal NC_PVDDCR_CPU0_P0_PWM8 at (B 2) is labeled only once in the design.
Signal NC_PVDDCR_CPU0_P0_PWM7 at (B 2) is labeled only once in the design.
Signal VSENSE_PVDDCR_CPU0_P0_VSEN0 at (B 3) is labeled only once in the design.
Signal PWRGD_PVDDCR_CPU0_P0_R at (B 3) is labeled only once in the design.
Signal PVDDCR_CPU0_P0_VMON at (A 3) is labeled only once in the design.
Signal PVDDCR_CPU0_P0_VINSEN at (A 3) is labeled only once in the design.
Signal VSENSE_PVDDCR_SOC_P0_VSEN1 at (B 3) is labeled only once in the design.
Signal NC_PVDDCR_CPU0_P0_PWM9 at (B 2) is labeled only once in the design.
Signal NC_PVDDCR_CPU0_P0_IMON9 at (B 2) is labeled only once in the design.
Signal PVDDCR_SOC_P0_EN//ADDR_CFG at (A 3) is labeled only once in the design.

Warnings in Page : @t6g_mb_lib.t6g(sch_1):Page194
Signal NC_PVDDCR_CPU0_P0_GL1_1 at (B 3) is labeled only once in the design.
Signal SW_PVDDCR_CPU0_P0_SW1 at (B 3) is labeled only once in the design.
Signal SW_PVDDCR_CPU0_P0_PH1 at (B 3) is labeled only once in the design.
Signal SW_PVDDCR_CPU0_P0_SW2_RC at (A 3) is labeled only once in the design.
Signal PVDDCR_CPU0_P0_VCC1 at (B 4) is labeled only once in the design.
Signal PVDDCR_CPU0_P0_VOS1 at (B 3) is labeled only once in the design.
Signal NC_PVDDCR_CPU0_P0_DNC2 at (A 4) is labeled only once in the design.
Signal PVDDCR_CPU0_P0_LSET2 at (A 4) is labeled only once in the design.
Signal NC_PVDDCR_CPU0_P0_GL2_2 at (A 3) is labeled only once in the design.
Signal NC_PVDDCR_CPU0_P0_GL1_2 at (A 3) is labeled only once in the design.
Signal PVDDCR_CPU0_P0_LSET1 at (B 4) is labeled only once in the design.
Signal PVDDCR_CPU0_P0_VOS2 at (A 3) is labeled only once in the design.
Signal SW_PVDDCR_CPU0_P0_SW2 at (A 3) is labeled only once in the design.
Signal SW_PVDDCR_CPU0_P0_PH2 at (A 3) is labeled only once in the design.
Signal SW_PVDDCR_CPU0_P0_SW1_RC at (B 3) is labeled only once in the design.
Signal NC_PVDDCR_CPU0_P0_GL2_1 at (B 3) is labeled only once in the design.
Signal PVDDCR_CPU0_P0_VCC2 at (A 4) is labeled only once in the design.
Signal NC_PVDDCR_CPU0_P0_DNC1 at (B 4) is labeled only once in the design.
Signal SW_PVDDCR_CPU0_P0_BOOT2 at (A 3) is labeled only once in the design.
Signal SW_PVDDCR_CPU0_P0_BOOT2_RC at (A 2) is labeled only once in the design.
Signal SW_PVDDCR_CPU0_P0_BOOT1_RC at (B 3) is labeled only once in the design.
Signal SW_PVDDCR_CPU0_P0_BOOT1 at (B 3) is labeled only once in the design.
Signal IND_CPU0_P0_CPL5 at (B 3) has too little display space.

Warnings in Page : @t6g_mb_lib.t6g(sch_1):Page195
Signal SW_PVDDCR_CPU0_P0_BOOT3_RC at (B 2) is labeled only once in the design.
Signal SW_PVDDCR_CPU0_P0_BOOT3 at (B 3) is labeled only once in the design.
Signal SW_PVDDCR_CPU0_P0_BOOT4_RC at (A 2) is labeled only once in the design.
Signal SW_PVDDCR_CPU0_P0_BOOT4 at (A 3) is labeled only once in the design.
Signal NC_PVDDCR_CPU0_P0_GL2_3 at (B 3) is labeled only once in the design.
Signal NC_PVDDCR_CPU0_P0_GL1_3 at (B 3) is labeled only once in the design.
Signal PVDDCR_CPU0_P0_VOS4 at (A 3) is labeled only once in the design.
Signal SW_PVDDCR_CPU0_P0_PH3 at (B 3) is labeled only once in the design.
Signal SW_PVDDCR_CPU0_P0_SW3_RC at (B 3) is labeled only once in the design.
Signal PVDDCR_CPU0_P0_VCC3 at (B 4) is labeled only once in the design.
Signal NC_PVDDCR_CPU0_P0_DNC3 at (B 4) is labeled only once in the design.
Signal PVDDCR_CPU0_P0_LSET3 at (B 4) is labeled only once in the design.
Signal PVDDCR_CPU0_P0_VOS3 at (B 3) is labeled only once in the design.
Signal SW_PVDDCR_CPU0_P0_SW4_RC at (A 3) is labeled only once in the design.
Signal NC_PVDDCR_CPU0_P0_GL1_4 at (A 3) is labeled only once in the design.
Signal NC_PVDDCR_CPU0_P0_GL2_4 at (A 3) is labeled only once in the design.
Signal SW_PVDDCR_CPU0_P0_SW4 at (A 3) is labeled only once in the design.
Signal PVDDCR_CPU0_P0_VCC4 at (A 4) is labeled only once in the design.
Signal NC_PVDDCR_CPU0_P0_DNC4 at (A 4) is labeled only once in the design.
Signal PVDDCR_CPU0_P0_LSET4 at (A 4) is labeled only once in the design.
Signal SW_PVDDCR_CPU0_P0_PH4 at (A 3) is labeled only once in the design.
Signal SW_PVDDCR_CPU0_P0_SW3 at (B 3) is labeled only once in the design.

Warnings in Page : @t6g_mb_lib.t6g(sch_1):Page196
Signal IND_CPU0_P0_CPL0 at (A 2) is labeled only once in the design.
Signal PVDDCR_CPU0_P0_LSET6 at (A 4) is labeled only once in the design.
Signal NC_PVDDCR_CPU0_P0_DNC6 at (A 4) is labeled only once in the design.
Signal NC_PVDDCR_CPU0_P0_GL2_6 at (A 3) is labeled only once in the design.
Signal NC_PVDDCR_CPU0_P0_GL1_6 at (A 3) is labeled only once in the design.
Signal SW_PVDDCR_CPU0_P0_SW6 at (A 3) is labeled only once in the design.
Signal PVDDCR_CPU0_P0_VOS6 at (A 3) is labeled only once in the design.
Signal SW_PVDDCR_CPU0_P0_SW6_RC at (A 3) is labeled only once in the design.
Signal PVDDCR_CPU0_P0_VOS5 at (B 3) is labeled only once in the design.
Signal PVDDCR_CPU0_P0_LSET5 at (B 4) is labeled only once in the design.
Signal NC_PVDDCR_CPU0_P0_DNC5 at (B 4) is labeled only once in the design.
Signal PVDDCR_CPU0_P0_VCC5 at (B 4) is labeled only once in the design.
Signal NC_PVDDCR_CPU0_P0_GL2_5 at (B 3) is labeled only once in the design.
Signal NC_PVDDCR_CPU0_P0_GL1_5 at (B 3) is labeled only once in the design.
Signal SW_PVDDCR_CPU0_P0_SW5 at (B 3) is labeled only once in the design.
Signal SW_PVDDCR_CPU0_P0_PH6 at (A 3) is labeled only once in the design.
Signal PVDDCR_CPU0_P0_VCC6 at (A 4) is labeled only once in the design.
Signal SW_PVDDCR_CPU0_P0_PH5 at (B 3) is labeled only once in the design.
Signal SW_PVDDCR_CPU0_P0_SW5_RC at (B 3) is labeled only once in the design.
Signal SW_PVDDCR_CPU0_P0_BOOT6 at (A 3) is labeled only once in the design.
Signal SW_PVDDCR_CPU0_P0_BOOT6_RC at (A 2) is labeled only once in the design.
Signal SW_PVDDCR_CPU0_P0_BOOT5 at (B 3) is labeled only once in the design.
Signal SW_PVDDCR_CPU0_P0_BOOT5_RC at (B 2) is labeled only once in the design.

Warnings in Page : @t6g_mb_lib.t6g(sch_1):Page198
Signal SW_PVDDCR_SOC_P0_BOOT2_RC at (A 2) is labeled only once in the design.
Signal SW_PVDDCR_SOC_P0_BOOT2 at (A 3) is labeled only once in the design.
Signal SW_PVDDCR_SOC_P0_BOOT1 at (B 3) is labeled only once in the design.
Signal PVDDCR_SOC_P0_VCC2 at (A 4) is labeled only once in the design.
Signal SW_PVDDCR_SOC_P0_SW2 at (A 3) is labeled only once in the design.
Signal SW_PVDDCR_SOC_P0_PH2 at (A 3) is labeled only once in the design.
Signal PVDDCR_SOC_P0_LSET2 at (A 4) is labeled only once in the design.
Signal NC_PVDDCR_SOC_P0_GL1_1 at (B 3) is labeled only once in the design.
Signal NC_PVDDCR_SOC_P0_GL2_1 at (B 3) is labeled only once in the design.
Signal PVDDCR_SOC_P0_LSET1 at (B 4) is labeled only once in the design.
Signal NC_PVDDCR_SOC_P0_DNC1 at (B 4) is labeled only once in the design.
Signal PVDDCR_SOC_P0_VOS1 at (B 3) is labeled only once in the design.
Signal SW_PVDDCR_SOC_P0_SW2_RC at (A 3) is labeled only once in the design.
Signal PVDDCR_SOC_P0_VOS2 at (A 3) is labeled only once in the design.
Signal NC_PVDDCR_SOC_P0_GL1_2 at (A 3) is labeled only once in the design.
Signal NC_PVDDCR_SOC_P0_GL2_2 at (A 3) is labeled only once in the design.
Signal NC_PVDDCR_SOC_P0_DNC2 at (A 4) is labeled only once in the design.
Signal PVDDCR_SOC_P0_VCC1 at (B 4) is labeled only once in the design.
Signal SW_PVDDCR_SOC_P0_PH1 at (B 3) is labeled only once in the design.
Signal SW_PVDDCR_SOC_P0_SW1 at (B 3) is labeled only once in the design.
Signal SW_PVDDCR_SOC_P0_BOOT1_RC at (B 2) is labeled only once in the design.
Signal SW_PVDDCR_SOC_P0_SW1_RC at (B 3) is labeled only once in the design.

Warnings in Page : @t6g_mb_lib.t6g(sch_1):Page199
Signal SW_PVDDCR_SOC_P0_SW3 at (B 3) is labeled only once in the design.
Signal NC_PVDDCR_SOC_P0_DNC3 at (B 4) is labeled only once in the design.
Signal PVDDCR_SOC_P0_LSET3 at (B 4) is labeled only once in the design.
Signal NC_PVDDCR_SOC_P0_GL1_3 at (B 3) is labeled only once in the design.
Signal NC_PVDDCR_SOC_P0_GL2_3 at (B 3) is labeled only once in the design.
Signal PVDDCR_SOC_P0_VOS3 at (B 3) is labeled only once in the design.
Signal SW_PVDDCR_SOC_P0_SW3_RC at (B 3) is labeled only once in the design.
Signal SW_PVDDCR_SOC_P0_PH3 at (B 3) is labeled only once in the design.
Signal IND_SOC_P0_CPL0 at (B 2) is labeled only once in the design.
Signal SW_PVDDCR_SOC_P0_BOOT3 at (B 3) is labeled only once in the design.
Signal SW_PVDDCR_SOC_P0_BOOT3_RC at (B 2) is labeled only once in the design.
Signal PVDDCR_SOC_P0_VCC3 at (B 4) is labeled only once in the design.

Warnings in Page : @t6g_mb_lib.t6g(sch_1):Page200
Signal SVID_PVDDCR_CPU1_P0_SVTI at (B 4) is labeled only once in the design.
Signal  PVDDIO_P0_EN_G at (A 4) is labeled only once in the design.
Signal  PVDDIO_P0_EN_R at (A 4) is labeled only once in the design.
Signal PVDDCR_CPU1_P0_VINSEN at (A 3) is labeled only once in the design.
Signal PVDDCR_CPU1_P0_RESET_N_R at (A 3) is labeled only once in the design.
Signal VSENSE_PVDDIO_P0_VSEN1 at (B 3) is labeled only once in the design.
Signal VSENSE_PVDDCR_CPU1_P0_VSEN0 at (B 3) is labeled only once in the design.
Signal PVDDCR_CPU1_P0_VCC at (B 2) is labeled only once in the design.
Signal SVID_PVDDCR_CPU1_P0_SVTI_R at (B 3) is labeled only once in the design.
Signal SMB_CLK_PVDDCR_CPU1_P0_R at (B 3) is labeled only once in the design.
Signal SVID_PVDDCR_CPU1_P0_SVC_R1 at (B 3) is labeled only once in the design.
Signal SVID_PVDDCR_CPU1_P0_SVTO_R at (B 3) is labeled only once in the design.
Signal NC_PVDDCR_CPU1_P0_IMON7 at (B 2) is labeled only once in the design.
Signal NC_PVDDCR_CPU1_P0_IMON8 at (B 2) is labeled only once in the design.
Signal PWRGD_PVDDIO_P0_R at (A 3) is labeled only once in the design.
Signal SVID_PVDDCR_CPU1_P0_SVD_R1 at (B 3) is labeled only once in the design.
Signal PVDDCR_CPU1_P0_SMB_ALERT_R at (B 3) is labeled only once in the design.
Signal PVDDCR_CPU1_P0_EN_R at (B 3) is labeled only once in the design.
Signal SMB_DIO_PVDDCR_CPU1_P0_R at (B 3) is labeled only once in the design.
Signal NC_PVDDCR_CPU1_P0_PWM8 at (B 2) is labeled only once in the design.
Signal NC_PVDDCR_CPU1_P0_PWM7 at (B 2) is labeled only once in the design.
Signal PWRGD_PVDDCR_CPU1_P0_R at (B 3) is labeled only once in the design.
Signal PVDDCR_CPU1_P0_VMON at (A 3) is labeled only once in the design.
Signal PVDDCR_CPU1_P0_OCP_N_R at (A 3) is labeled only once in the design.
Signal PVDDCR_CPU1_P0_EN1_ADDR_CFG at (A 3) is labeled only once in the design.

Warnings in Page : @t6g_mb_lib.t6g(sch_1):Page201
Signal SW_PVDDCR_CPU1_P0_SW1_RC at (B 3) is labeled only once in the design.
Signal SW_PVDDCR_CPU1_P0_SW1 at (B 3) is labeled only once in the design.
Signal PVDDCR_CPU1_P0_LSET2 at (A 4) is labeled only once in the design.
Signal NC_PVDDCR_CPU1_P0_DNC2 at (A 4) is labeled only once in the design.
Signal PVDDCR_CPU1_P0_VCC2 at (A 4) is labeled only once in the design.
Signal SW_PVDDCR_CPU1_P0_SW2 at (A 3) is labeled only once in the design.
Signal PVDDCR_CPU1_P0_VOS2 at (A 3) is labeled only once in the design.
Signal SW_PVDDCR_CPU1_P0_BOOTR2 at (A 3) is labeled only once in the design.
Signal NC_PVDDCR_CPU1_P0_GL1_2 at (A 3) is labeled only once in the design.
Signal NC_PVDDCR_CPU1_P0_GL2_2 at (A 3) is labeled only once in the design.
Signal SW_PVDDCR_CPU1_P0_SW2_RC at (A 3) is labeled only once in the design.
Signal PVDDCR_CPU1_P0_VOS1 at (B 3) is labeled only once in the design.
Signal PVDDCR_CPU1_P0_VCC1 at (B 4) is labeled only once in the design.
Signal NC_PVDDCR_CPU1_P0_DNC1 at (B 4) is labeled only once in the design.
Signal SW_PVDDCR_CPU1_P0_BOOTR1 at (B 3) is labeled only once in the design.
Signal NC_PVDDCR_CPU1_P0_GL1_1 at (B 3) is labeled only once in the design.
Signal PVDDCR_CPU1_P0_LSET1 at (B 4) is labeled only once in the design.
Signal NC_PVDDCR_CPU1_P0_GL2_1 at (B 3) is labeled only once in the design.
Signal SW_PVDDCR_CPU1_P0_BOOT2 at (A 3) is labeled only once in the design.
Signal SW_PVDDCR_CPU1_P0_BOOT2_R at (A 3) is labeled only once in the design.
Signal SW_PVDDCR_CPU1_P0_BOOT1 at (B 3) is labeled only once in the design.
Signal SW_PVDDCR_CPU1_P0_BOOT1_R at (B 3) is labeled only once in the design.

Warnings in Page : @t6g_mb_lib.t6g(sch_1):Page202
Signal SW_PVDDCR_CPU1_P0_SW3_RC at (B 3) is labeled only once in the design.
Signal SW_PVDDCR_CPU1_P0_BOOTR3 at (B 3) is labeled only once in the design.
Signal SW_PVDDCR_CPU1_P0_SW3 at (B 3) is labeled only once in the design.
Signal SW_PVDDCR_CPU1_P0_SW4_RC at (A 3) is labeled only once in the design.
Signal NC_PVDDCR_CPU1_P0_GL2_3 at (B 3) is labeled only once in the design.
Signal NC_PVDDCR_CPU1_P0_GL1_3 at (B 3) is labeled only once in the design.
Signal NC_PVDDCR_CPU1_P0_GL1_4 at (A 3) is labeled only once in the design.
Signal NC_PVDDCR_CPU1_P0_GL2_4 at (A 3) is labeled only once in the design.
Signal PVDDCR_CPU1_P0_VOS4 at (A 3) is labeled only once in the design.
Signal PVDDCR_CPU1_P0_VOS3 at (B 3) is labeled only once in the design.
Signal NC_PVDDCR_CPU1_P0_DNC3 at (B 4) is labeled only once in the design.
Signal PVDDCR_CPU1_P0_VCC3 at (B 4) is labeled only once in the design.
Signal PVDDCR_CPU1_P0_LSET3 at (B 4) is labeled only once in the design.
Signal NC_PVDDCR_CPU1_P0_DNC4 at (A 4) is labeled only once in the design.
Signal PVDDCR_CPU1_P0_VCC4 at (A 4) is labeled only once in the design.
Signal PVDDCR_CPU1_P0_LSET4 at (A 4) is labeled only once in the design.
Signal SW_PVDDCR_CPU1_P0_SW4 at (A 3) is labeled only once in the design.
Signal SW_PVDDCR_CPU1_P0_BOOTR4 at (A 3) is labeled only once in the design.
Signal SW_PVDDCR_CPU1_P0_BOOT4 at (A 3) is labeled only once in the design.
Signal SW_PVDDCR_CPU1_P0_BOOT4_R at (A 3) is labeled only once in the design.
Signal SW_PVDDCR_CPU1_P0_BOOT3 at (B 3) is labeled only once in the design.
Signal SW_PVDDCR_CPU1_P0_BOOT3_R at (B 3) is labeled only once in the design.
Signal PVDDCR_CPU1_P0_PWM4 at (A 4) has too little display space.

Warnings in Page : @t6g_mb_lib.t6g(sch_1):Page203
Signal SW_PVDDCR_CPU1_P0_BOOT5 at (B 3) is labeled only once in the design.
Signal SW_PVDDCR_CPU1_P0_BOOTR5 at (B 3) is labeled only once in the design.
Signal SW_PVDDCR_CPU1_P0_BOOT5_R at (B 3) is labeled only once in the design.
Signal SW_PVDDCR_CPU1_P0_BOOT6_R at (A 3) is labeled only once in the design.
Signal SW_PVDDCR_CPU1_P0_BOOT6 at (A 3) is labeled only once in the design.
Signal IND_CPU1_P0_CPL0 at (A 2) is labeled only once in the design.
Signal NC_PVDDCR_CPU1_P0_GL2_5 at (B 3) is labeled only once in the design.
Signal PVDDCR_CPU1_P0_LSET6 at (A 4) is labeled only once in the design.
Signal NC_PVDDCR_CPU1_P0_DNC6 at (A 4) is labeled only once in the design.
Signal PVDDCR_CPU1_P0_VCC6 at (A 4) is labeled only once in the design.
Signal PVDDCR_CPU1_P0_LSET5 at (B 4) is labeled only once in the design.
Signal PVDDCR_CPU1_P0_VCC5 at (B 4) is labeled only once in the design.
Signal NC_PVDDCR_CPU1_P0_DNC5 at (B 4) is labeled only once in the design.
Signal SW_PVDDCR_CPU1_P0_SW5 at (B 3) is labeled only once in the design.
Signal NC_PVDDCR_CPU1_P0_GL1_5 at (B 3) is labeled only once in the design.
Signal SW_PVDDCR_CPU1_P0_BOOTR6 at (A 3) is labeled only once in the design.
Signal NC_PVDDCR_CPU1_P0_GL1_6 at (A 3) is labeled only once in the design.
Signal NC_PVDDCR_CPU1_P0_GL2_6 at (A 3) is labeled only once in the design.
Signal SW_PVDDCR_CPU1_P0_SW6_RC at (A 3) is labeled only once in the design.
Signal PVDDCR_CPU1_P0_VOS6 at (A 3) is labeled only once in the design.
Signal PVDDCR_CPU1_P0_VOS5 at (B 3) is labeled only once in the design.
Signal SW_PVDDCR_CPU1_P0_SW5_RC at (B 3) is labeled only once in the design.
Signal SW_PVDDCR_CPU1_P0_SW6 at (A 3) is labeled only once in the design.

Warnings in Page : @t6g_mb_lib.t6g(sch_1):Page205
Signal SW_PVDDIO_P0_BOOT1_R at (B 3) is labeled only once in the design.
Signal SW_PVDDIO_P0_BOOT2_R at (B 3) is labeled only once in the design.
Signal SW_PVDDIO_P0_BOOT2 at (B 3) is labeled only once in the design.
Signal NC_PVDDIO_P0_DNC2 at (A 4) is labeled only once in the design.
Signal  PVDDIO_P0_VCC2 at (B 4) is labeled only once in the design.
Signal PVDDIO_P0_LSET2 at (A 4) is labeled only once in the design.
Signal  PVDDIO_P0_VOS2 at (A 3) is labeled only once in the design.
Signal NC_PVDDIO_P0_GL2_2 at (A 3) is labeled only once in the design.
Signal NC_PVDDIO_P0_GL1_2 at (A 3) is labeled only once in the design.
Signal  PVDDIO_P0_VCC1 at (B 4) is labeled only once in the design.
Signal PVDDIO_P0_LSET1 at (B 4) is labeled only once in the design.
Signal NC_PVDDIO_P0_DNC1 at (B 4) is labeled only once in the design.
Signal  PVDDIO_P0_VOS1 at (B 3) is labeled only once in the design.
Signal NC_PVDDIO_P0_GL2_1 at (B 3) is labeled only once in the design.
Signal NC_PVDDIO_P0_GL1_1 at (B 3) is labeled only once in the design.
Signal SW_PVDDIO_P0_SW1 at (B 3) is labeled only once in the design.
Signal SW_PVDDIO_P0_BOOTR2 at (A 3) is labeled only once in the design.
Signal SW_PVDDIO_P0_SW2 at (A 3) is labeled only once in the design.
Signal SW_PVDDIO_P0_BOOTR1 at (B 3) is labeled only once in the design.
Signal SW_PVDDIO_P0_SW2_RC at (A 3) is labeled only once in the design.
Signal SW_PVDDIO_P0_SW1_RC at (B 3) is labeled only once in the design.
Signal SW_PVDDIO_P0_BOOT1 at (B 3) is labeled only once in the design.

Warnings in Page : @t6g_mb_lib.t6g(sch_1):Page206
Signal NC_PVDDIO_P0_GL1_3 at (B 3) is labeled only once in the design.
Signal  PVDDIO_P0_VCC4 at (A 4) is labeled only once in the design.
Signal PVDDIO_P0_LSET4 at (A 4) is labeled only once in the design.
Signal NC_PVDDIO_P0_DNC4 at (A 4) is labeled only once in the design.
Signal NC_PVDDIO_P0_GL1_4 at (A 3) is labeled only once in the design.
Signal NC_PVDDIO_P0_GL2_4 at (A 3) is labeled only once in the design.
Signal  PVDDIO_P0_VOS4 at (A 3) is labeled only once in the design.
Signal  PVDDIO_P0_VCC3 at (B 4) is labeled only once in the design.
Signal PVDDIO_P0_LSET3 at (B 4) is labeled only once in the design.
Signal NC_PVDDIO_P0_DNC3 at (B 4) is labeled only once in the design.
Signal  PVDDIO_P0_VOS3 at (B 3) is labeled only once in the design.
Signal NC_PVDDIO_P0_GL2_3 at (B 3) is labeled only once in the design.
Signal SW_PVDDIO_P0_SW3 at (B 3) is labeled only once in the design.
Signal SW_PVDDIO_P0_SW4_RC at (A 3) is labeled only once in the design.
Signal IND_PVDDIO_P0_CPL0 at (A 3) is labeled only once in the design.
Signal SW_PVDDIO_P0_SW3_RC at (B 3) is labeled only once in the design.
Signal SW_PVDDIO_P0_SW4 at (A 3) is labeled only once in the design.
Signal SW_PVDDIO_P0_BOOTR4 at (A 3) is labeled only once in the design.
Signal SW_PVDDIO_P0_BOOTR3 at (B 3) is labeled only once in the design.
Signal SW_PVDDIO_P0_BOOT4 at (A 3) is labeled only once in the design.
Signal SW_PVDDIO_P0_BOOT4_R at (A 3) is labeled only once in the design.
Signal SW_PVDDIO_P0_BOOT3 at (B 3) is labeled only once in the design.
Signal SW_PVDDIO_P0_BOOT3_R at (B 3) is labeled only once in the design.

Warnings in Page : @t6g_mb_lib.t6g(sch_1):Page207
Signal NC_PVDD11_S3_P0_IMON8 at (A 2) is labeled only once in the design.
Signal NC_PVDD11_S3_P0_PWM8 at (A 2) is labeled only once in the design.
Signal PVDD11_S3_P0_TEMP1 at (A 2) is labeled only once in the design.
Signal PVDD11_S3_P0_ADDR_CFG at (A 3) is labeled only once in the design.
Signal PVDD11_S3_P0_OCP_N_R at (A 3) is labeled only once in the design.
Signal NC_PVDD11_S3_P0_IMON6 at (B 2) is labeled only once in the design.
Signal NC_PVDD11_S3_P0_PWM6 at (B 2) is labeled only once in the design.
Signal NC_PVDD11_S3_P0_IMON5 at (B 2) is labeled only once in the design.
Signal NC_PVDD11_S3_P0_PWM5 at (B 2) is labeled only once in the design.
Signal NC_PVDD11_S3_P0_IMON7 at (A 2) is labeled only once in the design.
Signal PVDD11_S3_P0_VDDIO at (A 3) is labeled only once in the design.
Signal PVDD11_S3_P0_VINSEN at (A 3) is labeled only once in the design.
Signal PVDD11_S3_P0_VMON at (A 3) is labeled only once in the design.
Signal PWRGD_PVDD11_S3_P0_R at (B 3) is labeled only once in the design.
Signal NC_PVDD11_S3_P0_PWM7 at (A 2) is labeled only once in the design.
Signal VSENSE_PVDD11_S3_P0_R at (B 3) is labeled only once in the design.
Signal NC_PVDD11_S3_P0_PWM3 at (B 2) is labeled only once in the design.
Signal NC_PVDD11_S3_P0_PWM4 at (B 2) is labeled only once in the design.
Signal PVDD11_S3_P0_PMSDA_R at (B 3) is labeled only once in the design.
Signal PVDD11_S3_P0_EN_R at (B 3) is labeled only once in the design.
Signal PVDD11_S3_P0_PMALERT_R at (B 3) is labeled only once in the design.
Signal NC_PVDD11_S3_P0_PG1 at (A 3) is labeled only once in the design.
Signal NC_PVDD11_S3_P0_IMON4 at (B 2) is labeled only once in the design.
Signal NC_PVDD11_S3_P0_IMON3 at (B 2) is labeled only once in the design.
Signal PVDD11_S3_P0_RESET_N_R at (A 2) is labeled only once in the design.
Signal NC_PVDD11_S3_P0_SVTO at (B 3) is labeled only once in the design.
Signal PVDD11_S3_P0_PMSCL_R at (B 3) is labeled only once in the design.
Signal PVDD11_S3_P0_VCC at (B 2) is labeled only once in the design.

Warnings in Page : @t6g_mb_lib.t6g(sch_1):Page208
Signal SW_PVDD11_S3_P0_BOOT1 at (B 3) is labeled only once in the design.
Signal SW_PVDD11_S3_P0_PH1 at (B 3) is labeled only once in the design.
Signal SW_PVDD11_S3_P0_BOOT1_RC at (B 2) is labeled only once in the design.
Signal SW_PVDD11_S3_P0_BOOT2_RC at (A 2) is labeled only once in the design.
Signal SW_PVDD11_S3_P0_BOOT2 at (A 3) is labeled only once in the design.
Signal NC_PVDD11_S3_P0_GL2_1 at (B 3) is labeled only once in the design.
Signal NC_PVDD11_S3_P0_GL1_1 at (B 3) is labeled only once in the design.
Signal PVDD11_S3_P0_VOS1 at (B 3) is labeled only once in the design.
Signal SW_PVDD11_S3_P0_PH2 at (A 3) is labeled only once in the design.
Signal PVDD11_S3_P0_VOS2 at (A 3) is labeled only once in the design.
Signal SW_PVDD11_S3_P0_SW1 at (B 3) is labeled only once in the design.
Signal PVDD11_S3_P0_LSET1 at (B 4) is labeled only once in the design.
Signal NC_PVDD11_S3_P0_DNC1 at (B 4) is labeled only once in the design.
Signal PVDD11_S3_P0_VCC1 at (B 4) is labeled only once in the design.
Signal SW_PVDD11_S3_P0_SW2_RC at (A 3) is labeled only once in the design.
Signal SW_PVDD11_S3_P0_SW2 at (A 3) is labeled only once in the design.
Signal NC_PVDD11_S3_P0_GL1_2 at (A 3) is labeled only once in the design.
Signal NC_PVDD11_S3_P0_GL2_2 at (A 3) is labeled only once in the design.
Signal PVDD11_S3_P0_VCC2 at (A 4) is labeled only once in the design.
Signal PVDD11_S3_P0_LSET2 at (A 4) is labeled only once in the design.
Signal NC_PVDD11_S3_P0_DNC2 at (A 4) is labeled only once in the design.
Signal SW_PVDD11_S3_P0_SW1_RC at (B 3) is labeled only once in the design.

Warnings in Page : @t6g_mb_lib.t6g(sch_1):Page209
Signal PVDD18_S5_P0_VCC at (B 4) is labeled only once in the design.
Signal PVDD18_S5_P0_REF at (B 3) is labeled only once in the design.
Signal PVDD18_S5_P0_CS at (B 4) is labeled only once in the design.
Signal PVDD18_S5_P0_MODE at (B 4) is labeled only once in the design.
Signal PVDD18_S5_P0_FB_RC at (B 2) is labeled only once in the design.
Signal SW_P12V_AUX_PVDD18_S5_P0_FLT at (B 4) is labeled only once in the design.
Signal PVDD18_S5_P0_FB at (B 3) is labeled only once in the design.
Signal PVDD18_S5_P0_RGND at (B 3) is labeled only once in the design.
Signal SW_PVDD18_S5_P0_SW at (B 3) is labeled only once in the design.
Signal SW_PVDD18_S5_P0_BST at (B 3) is labeled only once in the design.
Signal SW_PVDD18_S5_P0_BST_R at (B 3) is labeled only once in the design.
Signal PWRGD_PVDD18_S5_P0 at (B 3) is labeled only once in the design.

Warnings in Page : @t6g_mb_lib.t6g(sch_1):Page210
Signal PVDDCR_SOC_P1_EN_GD at (A 4) is labeled only once in the design.
Signal PVDDCR_CPU0_P1_VCC at (B 2) is labeled only once in the design.
Signal PWRGD_PVDDCR_SOC_P1_R at (A 3) is labeled only once in the design.
Signal PVDDCR_CPU0_P1_OCP_N_R at (A 3) is labeled only once in the design.
Signal PVDDCR_SOC_P1_EN_RC at (A 4) is labeled only once in the design.
Signal SVID_PVDDCR_CPU0_P1_SVTI at (B 4) is labeled only once in the design.
Signal SVID_PVDDCR_CPU0_P1_SVTI_R at (B 3) is labeled only once in the design.
Signal PVDDCR_CPU0_P1_PMSCL_R at (B 3) is labeled only once in the design.
Signal SVID_PVDDCR_CPU0_P1_SVC_R1 at (B 3) is labeled only once in the design.
Signal SVID_PVDDCR_CPU0_P1_SVTO_R at (B 3) is labeled only once in the design.
Signal PVDDCR_CPU0_P1_RESET_N_R at (A 3) is labeled only once in the design.
Signal NC_PVDDCR_CPU0_P1_IMON7 at (B 2) is labeled only once in the design.
Signal NC_PVDDCR_CPU0_P1_IMON8 at (B 2) is labeled only once in the design.
Signal SVID_PVDDCR_CPU0_P1_SVD_R1 at (B 3) is labeled only once in the design.
Signal PVDDCR_CPU0_P1_PMALERT_R at (B 3) is labeled only once in the design.
Signal PVDDCR_CPU0_P1_EN_R at (B 3) is labeled only once in the design.
Signal PVDDCR_CPU0_P1_PMSDA_R at (B 3) is labeled only once in the design.
Signal NC_PVDDCR_CPU0_P1_PWM8 at (B 2) is labeled only once in the design.
Signal NC_PVDDCR_CPU0_P1_PWM7 at (B 2) is labeled only once in the design.
Signal VSENSE_PVDDCR_CPU0_P1_VSEN0 at (B 3) is labeled only once in the design.
Signal PWRGD_PVDDCR_CPU0_P1_R at (B 3) is labeled only once in the design.
Signal PVDDCR_CPU0_P1_VMON at (A 3) is labeled only once in the design.
Signal PVDDCR_CPU0_P1_VINSEN at (A 3) is labeled only once in the design.
Signal VSENSE_PVDDCR_SOC_P1_VSEN1 at (B 3) is labeled only once in the design.
Signal NC_PVDDCR_CPU0_P1_PWM9 at (B 2) is labeled only once in the design.
Signal NC_PVDDCR_CPU0_P1_IMON9 at (B 2) is labeled only once in the design.
Signal PVDDCR_SOC_P1_EN//ADDR_CFG at (A 3) is labeled only once in the design.

Warnings in Page : @t6g_mb_lib.t6g(sch_1):Page211
Signal SW_PVDDCR_CPU0_P1_SW1_RC at (B 3) is labeled only once in the design.
Signal NC_PVDDCR_CPU0_P1_DNC1 at (B 4) is labeled only once in the design.
Signal SW_PVDDCR_CPU0_P1_SW2_RC at (A 3) is labeled only once in the design.
Signal PVDDCR_CPU0_P1_VCC1 at (B 4) is labeled only once in the design.
Signal PVDDCR_CPU0_P1_VOS1 at (B 3) is labeled only once in the design.
Signal PVDDCR_CPU0_P1_LSET2 at (A 4) is labeled only once in the design.
Signal NC_PVDDCR_CPU0_P1_DNC2 at (A 4) is labeled only once in the design.
Signal NC_PVDDCR_CPU0_P1_GL1_2 at (A 3) is labeled only once in the design.
Signal NC_PVDDCR_CPU0_P1_GL2_2 at (A 3) is labeled only once in the design.
Signal PVDDCR_CPU0_P1_VOS2 at (A 3) is labeled only once in the design.
Signal PVDDCR_CPU0_P1_LSET1 at (B 4) is labeled only once in the design.
Signal NC_PVDDCR_CPU0_P1_GL2_1 at (B 3) is labeled only once in the design.
Signal NC_PVDDCR_CPU0_P1_GL1_1 at (B 3) is labeled only once in the design.
Signal PVDDCR_CPU0_P1_VCC2 at (B 4) is labeled only once in the design.
Signal SW_PVDDCR_CPU0_P1_PH1 at (B 3) is labeled only once in the design.
Signal SW_PVDDCR_CPU0_P1_PH2 at (A 3) is labeled only once in the design.
Signal SW_PVDDCR_CPU0_P1_SW1 at (B 3) is labeled only once in the design.
Signal SW_PVDDCR_CPU0_P1_SW2 at (A 3) is labeled only once in the design.
Signal SW_PVDDCR_CPU0_P1_BOOT1_RC at (B 2) is labeled only once in the design.
Signal SW_PVDDCR_CPU0_P1_BOOT2 at (B 3) is labeled only once in the design.
Signal SW_PVDDCR_CPU0_P1_BOOT2_RC at (B 2) is labeled only once in the design.
Signal SW_PVDDCR_CPU0_P1_BOOT1 at (B 3) is labeled only once in the design.

Warnings in Page : @t6g_mb_lib.t6g(sch_1):Page212
Signal SW_PVDDCR_CPU0_P1_SW3 at (B 3) is labeled only once in the design.
Signal NC_PVDDCR_CPU0_P1_DNC4 at (A 4) is labeled only once in the design.
Signal PVDDCR_CPU0_P1_LSET4 at (A 4) is labeled only once in the design.
Signal PVDDCR_CPU0_P1_VCC4 at (A 4) is labeled only once in the design.
Signal NC_PVDDCR_CPU0_P1_GL1_4 at (A 3) is labeled only once in the design.
Signal SW_PVDDCR_CPU0_P1_SW4 at (A 3) is labeled only once in the design.
Signal NC_PVDDCR_CPU0_P1_GL2_4 at (A 3) is labeled only once in the design.
Signal PVDDCR_CPU0_P1_VOS4 at (A 3) is labeled only once in the design.
Signal SW_PVDDCR_CPU0_P1_SW4_RC at (A 3) is labeled only once in the design.
Signal PVDDCR_CPU0_P1_VOS3 at (B 3) is labeled only once in the design.
Signal PVDDCR_CPU0_P1_LSET3 at (B 4) is labeled only once in the design.
Signal NC_PVDDCR_CPU0_P1_DNC3 at (B 4) is labeled only once in the design.
Signal NC_PVDDCR_CPU0_P1_GL2_3 at (B 3) is labeled only once in the design.
Signal NC_PVDDCR_CPU0_P1_GL1_3 at (B 3) is labeled only once in the design.
Signal SW_PVDDCR_CPU0_P1_SW3_RC at (B 3) is labeled only once in the design.
Signal SW_PVDDCR_CPU0_P1_PH4 at (A 3) is labeled only once in the design.
Signal SW_PVDDCR_CPU0_P1_BOOT4 at (A 3) is labeled only once in the design.
Signal SW_PVDDCR_CPU0_P1_BOOT4_RC at (A 2) is labeled only once in the design.
Signal SW_PVDDCR_CPU0_P1_BOOT3_RC at (B 2) is labeled only once in the design.
Signal PVDDCR_CPU0_P1_VCC3 at (B 4) is labeled only once in the design.
Signal SW_PVDDCR_CPU0_P1_PH3 at (B 3) is labeled only once in the design.
Signal SW_PVDDCR_CPU0_P1_BOOT3 at (B 3) is labeled only once in the design.

Warnings in Page : @t6g_mb_lib.t6g(sch_1):Page213
Signal SW_PVDDCR_CPU0_P1_BOOT5_RC at (B 2) is labeled only once in the design.
Signal SW_PVDDCR_CPU0_P1_BOOT5 at (B 3) is labeled only once in the design.
Signal SW_PVDDCR_CPU0_P1_BOOT6_RC at (A 2) is labeled only once in the design.
Signal SW_PVDDCR_CPU0_P1_BOOT6 at (A 3) is labeled only once in the design.
Signal IND_CPU0_P1_CPL0 at (A 2) is labeled only once in the design.
Signal SW_PVDDCR_CPU0_P1_PH6 at (A 3) is labeled only once in the design.
Signal SW_PVDDCR_CPU0_P1_PH5 at (B 3) is labeled only once in the design.
Signal NC_PVDDCR_CPU0_P1_GL1_5 at (B 3) is labeled only once in the design.
Signal PVDDCR_CPU0_P1_VCC5 at (B 4) is labeled only once in the design.
Signal NC_PVDDCR_CPU0_P1_DNC5 at (B 4) is labeled only once in the design.
Signal SW_PVDDCR_CPU0_P1_SW6_RC at (A 3) is labeled only once in the design.
Signal PVDDCR_CPU0_P1_VOS6 at (A 3) is labeled only once in the design.
Signal SW_PVDDCR_CPU0_P1_SW6 at (A 3) is labeled only once in the design.
Signal NC_PVDDCR_CPU0_P1_GL1_6 at (A 3) is labeled only once in the design.
Signal NC_PVDDCR_CPU0_P1_GL2_6 at (A 3) is labeled only once in the design.
Signal PVDDCR_CPU0_P1_VCC6 at (A 4) is labeled only once in the design.
Signal PVDDCR_CPU0_P1_LSET6 at (A 4) is labeled only once in the design.
Signal NC_PVDDCR_CPU0_P1_DNC6 at (A 4) is labeled only once in the design.
Signal SW_PVDDCR_CPU0_P1_SW5_RC at (B 3) is labeled only once in the design.
Signal SW_PVDDCR_CPU0_P1_SW5 at (B 3) is labeled only once in the design.
Signal PVDDCR_CPU0_P1_LSET5 at (B 4) is labeled only once in the design.
Signal NC_PVDDCR_CPU0_P1_GL2_5 at (B 3) is labeled only once in the design.
Signal PVDDCR_CPU0_P1_VOS5 at (B 3) is labeled only once in the design.

Warnings in Page : @t6g_mb_lib.t6g(sch_1):Page215
Signal SW_PVDDCR_SOC_P1_PH1 at (B 3) is labeled only once in the design.
Signal PVDDCR_SOC_P1_VCC1 at (B 4) is labeled only once in the design.
Signal PVDDCR_SOC_P1_LSET2 at (A 4) is labeled only once in the design.
Signal NC_PVDDCR_SOC_P1_DNC2 at (A 4) is labeled only once in the design.
Signal PVDDCR_SOC_P1_VCC2 at (A 4) is labeled only once in the design.
Signal SW_PVDDCR_SOC_P1_SW2 at (A 3) is labeled only once in the design.
Signal NC_PVDDCR_SOC_P1_GL2_2 at (A 3) is labeled only once in the design.
Signal NC_PVDDCR_SOC_P1_GL1_2 at (A 3) is labeled only once in the design.
Signal SW_PVDDCR_SOC_P1_SW2_RC at (A 3) is labeled only once in the design.
Signal NC_PVDDCR_SOC_P1_DNC1 at (B 4) is labeled only once in the design.
Signal PVDDCR_SOC_P1_LSET1 at (B 4) is labeled only once in the design.
Signal SW_PVDDCR_SOC_P1_SW1 at (B 3) is labeled only once in the design.
Signal NC_PVDDCR_SOC_P1_GL2_1 at (B 3) is labeled only once in the design.
Signal SW_PVDDCR_SOC_P1_PH2 at (A 3) is labeled only once in the design.
Signal PVDDCR_SOC_P1_VOS2 at (A 3) is labeled only once in the design.
Signal NC_PVDDCR_SOC_P1_GL1_1 at (B 3) is labeled only once in the design.
Signal PVDDCR_SOC_P1_VOS1 at (B 3) is labeled only once in the design.
Signal SW_PVDDCR_SOC_P1_BOOT2 at (A 3) is labeled only once in the design.
Signal SW_PVDDCR_SOC_P1_BOOT2_RC at (A 2) is labeled only once in the design.
Signal SW_PVDDCR_SOC_P1_BOOT1 at (B 3) is labeled only once in the design.
Signal SW_PVDDCR_SOC_P1_BOOT1_RC at (B 2) is labeled only once in the design.
Signal SW_PVDDCR_SOC_P1_SW1_RC at (B 3) is labeled only once in the design.

Warnings in Page : @t6g_mb_lib.t6g(sch_1):Page216
Signal SW_PVDDCR_SOC_P1_SW3_RC at (B 3) is labeled only once in the design.
Signal IND_SOC_P1_CPL0 at (B 2) is labeled only once in the design.
Signal PVDDCR_SOC_P1_VCC3 at (B 4) is labeled only once in the design.
Signal NC_PVDDCR_SOC_P1_DNC3 at (B 4) is labeled only once in the design.
Signal PVDDCR_SOC_P1_LSET3 at (B 4) is labeled only once in the design.
Signal NC_PVDDCR_SOC_P1_GL1_3 at (B 3) is labeled only once in the design.
Signal NC_PVDDCR_SOC_P1_GL2_3 at (B 3) is labeled only once in the design.
Signal SW_PVDDCR_SOC_P1_BOOT3_RC at (B 2) is labeled only once in the design.
Signal PVDDCR_SOC_P1_VOS3 at (B 3) is labeled only once in the design.
Signal SW_PVDDCR_SOC_P1_SW3 at (B 3) is labeled only once in the design.
Signal SW_PVDDCR_SOC_P1_PH3 at (B 3) is labeled only once in the design.
Signal SW_PVDDCR_SOC_P1_BOOT3 at (B 3) is labeled only once in the design.

Warnings in Page : @t6g_mb_lib.t6g(sch_1):Page217
Signal PVDDCR_CPU1_P1_EN1_ADDR_CFG at (A 3) is labeled only once in the design.
Signal PVDDCR_CPU1_P1_OCP_N_R at (A 3) is labeled only once in the design.
Signal PVDDCR_CPU1_P1_VMON at (A 3) is labeled only once in the design.
Signal PWRGD_PVDDCR_CPU1_P1_R at (B 3) is labeled only once in the design.
Signal NC_PVDDCR_CPU1_P1_PWM7 at (B 2) is labeled only once in the design.
Signal NC_PVDDCR_CPU1_P1_PWM8 at (B 2) is labeled only once in the design.
Signal SMB_DIO_PVDDCR_CPU1_P1_R at (B 3) is labeled only once in the design.
Signal PVDDCR_CPU1_P1_EN_R at (B 3) is labeled only once in the design.
Signal PVDDCR_CPU1_P1_SMB_ALERT_R at (B 3) is labeled only once in the design.
Signal SVID_PVDDCR_CPU1_P1_SVD_R1 at (B 3) is labeled only once in the design.
Signal PWRGD_PVDDIO_P1_R at (A 3) is labeled only once in the design.
Signal NC_PVDDCR_CPU1_P1_IMON8 at (B 2) is labeled only once in the design.
Signal NC_PVDDCR_CPU1_P1_IMON7 at (B 2) is labeled only once in the design.
Signal SVID_PVDDCR_CPU1_P1_SVTO_R at (B 3) is labeled only once in the design.
Signal SVID_PVDDCR_CPU1_P1_SVC_R1 at (B 3) is labeled only once in the design.
Signal SMB_CLK_PVDDCR_CPU1_P1_R at (B 3) is labeled only once in the design.
Signal SVID_PVDDCR_CPU1_P1_SVTI_R at (B 3) is labeled only once in the design.
Signal PVDDCR_CPU1_P1_VCC at (B 2) is labeled only once in the design.
Signal SVID_PVDDCR_CPU1_P1_SVTI at (B 4) is labeled only once in the design.
Signal VSENSE_PVDDIO_P1_VSEN1 at (B 3) is labeled only once in the design.
Signal VSENSE_PVDDCR_CPU1_P1_VSEN0 at (B 3) is labeled only once in the design.
Signal  PVDDIO_P1_EN_R at (A 4) is labeled only once in the design.
Signal PVDDCR_CPU1_P1_VINSEN at (A 3) is labeled only once in the design.
Signal  PVDDIO_P1_EN_G at (A 4) is labeled only once in the design.
Signal PVDDCR_CPU1_P1_RESET_N_R at (A 3) is labeled only once in the design.

Warnings in Page : @t6g_mb_lib.t6g(sch_1):Page218
Signal SW_PVDDCR_CPU1_P1_BOOT2 at (B 3) is labeled only once in the design.
Signal SW_PVDDCR_CPU1_P1_BOOT1_R at (B 3) is labeled only once in the design.
Signal SW_PVDDCR_CPU1_P1_BOOT1 at (B 3) is labeled only once in the design.
Signal SW_PVDDCR_CPU1_P1_BOOT2_R at (B 3) is labeled only once in the design.
Signal PVDDCR_CPU1_P1_LSET1 at (B 4) is labeled only once in the design.
Signal SW_PVDDCR_CPU1_P1_SW2 at (A 3) is labeled only once in the design.
Signal PVDDCR_CPU1_P1_VOS1 at (B 3) is labeled only once in the design.
Signal NC_PVDDCR_CPU1_P1_GL2_1 at (B 3) is labeled only once in the design.
Signal NC_PVDDCR_CPU1_P1_GL1_1 at (B 3) is labeled only once in the design.
Signal SW_PVDDCR_CPU1_P1_SW1 at (B 3) is labeled only once in the design.
Signal NC_PVDDCR_CPU1_P1_DNC1 at (B 4) is labeled only once in the design.
Signal SW_PVDDCR_CPU1_P1_SW2_RC at (A 3) is labeled only once in the design.
Signal NC_PVDDCR_CPU1_P1_GL1_2 at (A 3) is labeled only once in the design.
Signal NC_PVDDCR_CPU1_P1_GL2_2 at (A 3) is labeled only once in the design.
Signal PVDDCR_CPU1_P1_VOS2 at (A 3) is labeled only once in the design.
Signal SW_PVDDCR_CPU1_P1_BOOTR2 at (A 3) is labeled only once in the design.
Signal PVDDCR_CPU1_P1_VCC2 at (B 4) is labeled only once in the design.
Signal NC_PVDDCR_CPU1_P1_DNC2 at (A 4) is labeled only once in the design.
Signal PVDDCR_CPU1_P1_LSET2 at (A 4) is labeled only once in the design.
Signal SW_PVDDCR_CPU1_P1_SW1_RC at (B 3) is labeled only once in the design.
Signal PVDDCR_CPU1_P1_VCC1 at (B 4) is labeled only once in the design.
Signal SW_PVDDCR_CPU1_P1_BOOTR1 at (B 3) is labeled only once in the design.

Warnings in Page : @t6g_mb_lib.t6g(sch_1):Page219
Signal SW_PVDDCR_CPU1_P1_SW4_RC at (A 3) is labeled only once in the design.
Signal PVDDCR_CPU1_P1_VCC3 at (B 4) is labeled only once in the design.
Signal NC_PVDDCR_CPU1_P1_DNC3 at (B 4) is labeled only once in the design.
Signal PVDDCR_CPU1_P1_LSET3 at (B 4) is labeled only once in the design.
Signal NC_PVDDCR_CPU1_P1_DNC4 at (A 4) is labeled only once in the design.
Signal PVDDCR_CPU1_P1_VCC4 at (A 4) is labeled only once in the design.
Signal PVDDCR_CPU1_P1_LSET4 at (A 4) is labeled only once in the design.
Signal NC_PVDDCR_CPU1_P1_GL2_4 at (A 3) is labeled only once in the design.
Signal NC_PVDDCR_CPU1_P1_GL1_4 at (A 3) is labeled only once in the design.
Signal PVDDCR_CPU1_P1_VOS4 at (A 3) is labeled only once in the design.
Signal SW_PVDDCR_CPU1_P1_SW4 at (A 3) is labeled only once in the design.
Signal SW_PVDDCR_CPU1_P1_BOOTR4 at (A 3) is labeled only once in the design.
Signal NC_PVDDCR_CPU1_P1_GL2_3 at (B 3) is labeled only once in the design.
Signal NC_PVDDCR_CPU1_P1_GL1_3 at (B 3) is labeled only once in the design.
Signal PVDDCR_CPU1_P1_VOS3 at (B 3) is labeled only once in the design.
Signal SW_PVDDCR_CPU1_P1_SW3 at (B 3) is labeled only once in the design.
Signal SW_PVDDCR_CPU1_P1_BOOTR3 at (B 3) is labeled only once in the design.
Signal SW_PVDDCR_CPU1_P1_SW3_RC at (B 3) is labeled only once in the design.
Signal SW_PVDDCR_CPU1_P1_BOOT3 at (B 3) is labeled only once in the design.
Signal SW_PVDDCR_CPU1_P1_BOOT3_R at (B 3) is labeled only once in the design.
Signal SW_PVDDCR_CPU1_P1_BOOT4 at (A 3) is labeled only once in the design.
Signal SW_PVDDCR_CPU1_P1_BOOT4_R at (A 3) is labeled only once in the design.
Signal PVDDCR_CPU1_P1_PWM4 at (A 4) has too little display space.
Signal PVDDCR_CPU1_P1_PWM3 at (B 4) has too little display space.

Warnings in Page : @t6g_mb_lib.t6g(sch_1):Page220
Signal PVDDCR_CPU1_P1_VOS5 at (B 3) is labeled only once in the design.
Signal SW_PVDDCR_CPU1_P1_SW5_RC at (B 3) is labeled only once in the design.
Signal PVDDCR_CPU1_P1_VOS6 at (A 3) is labeled only once in the design.
Signal SW_PVDDCR_CPU1_P1_SW6_RC at (A 3) is labeled only once in the design.
Signal NC_PVDDCR_CPU1_P1_GL1_5 at (B 3) is labeled only once in the design.
Signal NC_PVDDCR_CPU1_P1_DNC5 at (B 4) is labeled only once in the design.
Signal PVDDCR_CPU1_P1_VCC5 at (B 4) is labeled only once in the design.
Signal PVDDCR_CPU1_P1_LSET5 at (B 4) is labeled only once in the design.
Signal PVDDCR_CPU1_P1_VCC6 at (A 4) is labeled only once in the design.
Signal NC_PVDDCR_CPU1_P1_DNC6 at (A 4) is labeled only once in the design.
Signal PVDDCR_CPU1_P1_LSET6 at (A 4) is labeled only once in the design.
Signal NC_PVDDCR_CPU1_P1_GL2_5 at (B 3) is labeled only once in the design.
Signal SW_PVDDCR_CPU1_P1_SW5 at (B 3) is labeled only once in the design.
Signal SW_PVDDCR_CPU1_P1_BOOTR5 at (B 3) is labeled only once in the design.
Signal IND_CPU1_P1_CPL0 at (A 2) is labeled only once in the design.
Signal SW_PVDDCR_CPU1_P1_BOOT6_R at (A 3) is labeled only once in the design.
Signal SW_PVDDCR_CPU1_P1_BOOT5 at (B 3) is labeled only once in the design.
Signal SW_PVDDCR_CPU1_P1_BOOT5_R at (B 3) is labeled only once in the design.
Signal NC_PVDDCR_CPU1_P1_GL2_6 at (A 3) is labeled only once in the design.
Signal NC_PVDDCR_CPU1_P1_GL1_6 at (A 3) is labeled only once in the design.
Signal SW_PVDDCR_CPU1_P1_SW6 at (A 3) is labeled only once in the design.
Signal SW_PVDDCR_CPU1_P1_BOOTR6 at (A 3) is labeled only once in the design.
Signal SW_PVDDCR_CPU1_P1_BOOT6 at (A 3) is labeled only once in the design.

Warnings in Page : @t6g_mb_lib.t6g(sch_1):Page222
Signal SW_PVDDIO_P1_BOOT1_R at (B 3) is labeled only once in the design.
Signal SW_PVDDIO_P1_BOOT2_R at (B 3) is labeled only once in the design.
Signal SW_PVDDIO_P1_BOOT2 at (B 3) is labeled only once in the design.
Signal SW_PVDDIO_P1_SW2_RC at (A 3) is labeled only once in the design.
Signal  PVDDIO_P1_VCC2 at (B 4) is labeled only once in the design.
Signal NC_PVDDIO_P1_DNC2 at (A 4) is labeled only once in the design.
Signal SW_PVDDIO_P1_SW1_RC at (B 3) is labeled only once in the design.
Signal NC_PVDDIO_P1_GL2_1 at (B 3) is labeled only once in the design.
Signal PVDDIO_P1_LSET1 at (B 4) is labeled only once in the design.
Signal SW_PVDDIO_P1_BOOTR1 at (B 3) is labeled only once in the design.
Signal SW_PVDDIO_P1_SW1 at (B 3) is labeled only once in the design.
Signal PVDDIO_P1_LSET2 at (A 4) is labeled only once in the design.
Signal  PVDDIO_P1_VOS2 at (A 3) is labeled only once in the design.
Signal NC_PVDDIO_P1_GL2_2 at (A 3) is labeled only once in the design.
Signal NC_PVDDIO_P1_GL1_2 at (A 3) is labeled only once in the design.
Signal  PVDDIO_P1_VCC1 at (B 4) is labeled only once in the design.
Signal NC_PVDDIO_P1_DNC1 at (B 4) is labeled only once in the design.
Signal NC_PVDDIO_P1_GL1_1 at (B 3) is labeled only once in the design.
Signal  PVDDIO_P1_VOS1 at (B 3) is labeled only once in the design.
Signal SW_PVDDIO_P1_SW2 at (A 3) is labeled only once in the design.
Signal SW_PVDDIO_P1_BOOTR2 at (A 3) is labeled only once in the design.
Signal SW_PVDDIO_P1_BOOT1 at (B 3) is labeled only once in the design.

Warnings in Page : @t6g_mb_lib.t6g(sch_1):Page223
Signal NC_PVDDIO_P1_DNC4 at (A 4) is labeled only once in the design.
Signal  PVDDIO_P1_VCC4 at (A 4) is labeled only once in the design.
Signal PVDDIO_P1_LSET4 at (A 4) is labeled only once in the design.
Signal NC_PVDDIO_P1_GL1_4 at (A 3) is labeled only once in the design.
Signal NC_PVDDIO_P1_GL2_4 at (A 3) is labeled only once in the design.
Signal  PVDDIO_P1_VOS4 at (A 3) is labeled only once in the design.
Signal PVDDIO_P1_LSET3 at (B 4) is labeled only once in the design.
Signal NC_PVDDIO_P1_DNC3 at (B 4) is labeled only once in the design.
Signal  PVDDIO_P1_VCC3 at (B 4) is labeled only once in the design.
Signal  PVDDIO_P1_VOS3 at (B 3) is labeled only once in the design.
Signal NC_PVDDIO_P1_GL2_3 at (B 3) is labeled only once in the design.
Signal NC_PVDDIO_P1_GL1_3 at (B 3) is labeled only once in the design.
Signal SW_PVDDIO_P1_BOOTR4 at (A 3) is labeled only once in the design.
Signal SW_PVDDIO_P1_SW3 at (B 3) is labeled only once in the design.
Signal SW_PVDDIO_P1_SW4 at (A 3) is labeled only once in the design.
Signal SW_PVDDIO_P1_BOOTR3 at (B 3) is labeled only once in the design.
Signal SW_PVDDIO_P1_SW4_RC at (A 3) is labeled only once in the design.
Signal IND_PVDDIO_P1_CPL0 at (A 2) is labeled only once in the design.
Signal SW_PVDDIO_P1_BOOT4 at (A 3) is labeled only once in the design.
Signal SW_PVDDIO_P1_BOOT4_R at (A 3) is labeled only once in the design.
Signal SW_PVDDIO_P1_BOOT3 at (B 3) is labeled only once in the design.
Signal SW_PVDDIO_P1_BOOT3_R at (B 3) is labeled only once in the design.
Signal SW_PVDDIO_P1_SW3_RC at (B 3) is labeled only once in the design.

Warnings in Page : @t6g_mb_lib.t6g(sch_1):Page224
Signal PVDD11_S3_P1_VCC at (B 2) is labeled only once in the design.
Signal PVDD11_S3_P1_PMSCL_R at (B 3) is labeled only once in the design.
Signal NC_PVDD11_S3_P1_SVTO at (B 3) is labeled only once in the design.
Signal PVDD11_S3_P1_RESET_N_R at (A 2) is labeled only once in the design.
Signal NC_PVDD11_S3_P1_IMON3 at (B 2) is labeled only once in the design.
Signal NC_PVDD11_S3_P1_IMON4 at (B 2) is labeled only once in the design.
Signal NC_PVDD11_S3_P1_PG1 at (A 3) is labeled only once in the design.
Signal PVDD11_S3_P1_PMALERT_R at (B 3) is labeled only once in the design.
Signal PVDD11_S3_P1_EN_R at (B 3) is labeled only once in the design.
Signal PVDD11_S3_P1_PMSDA_R at (B 3) is labeled only once in the design.
Signal NC_PVDD11_S3_P1_PWM4 at (B 2) is labeled only once in the design.
Signal NC_PVDD11_S3_P1_PWM3 at (B 2) is labeled only once in the design.
Signal VSENSE_PVDD11_S3_P1_R at (B 3) is labeled only once in the design.
Signal NC_PVDD11_S3_P1_PWM7 at (A 2) is labeled only once in the design.
Signal PWRGD_PVDD11_S3_P1_R at (B 3) is labeled only once in the design.
Signal PVDD11_S3_P1_VMON at (A 3) is labeled only once in the design.
Signal PVDD11_S3_P1_VINSEN at (A 3) is labeled only once in the design.
Signal PVDD11_S3_P1_VDDIO at (A 3) is labeled only once in the design.
Signal NC_PVDD11_S3_P1_IMON7 at (A 2) is labeled only once in the design.
Signal NC_PVDD11_S3_P1_PWM5 at (B 2) is labeled only once in the design.
Signal NC_PVDD11_S3_P1_IMON5 at (B 2) is labeled only once in the design.
Signal NC_PVDD11_S3_P1_PWM6 at (B 2) is labeled only once in the design.
Signal NC_PVDD11_S3_P1_IMON6 at (B 2) is labeled only once in the design.
Signal PVDD11_S3_P1_OCP_N_R at (A 3) is labeled only once in the design.
Signal PVDD11_S3_P1_ADDR_CFG at (A 3) is labeled only once in the design.
Signal PVDD11_S3_P1_TEMP1 at (A 2) is labeled only once in the design.
Signal NC_PVDD11_S3_P1_PWM8 at (A 2) is labeled only once in the design.
Signal NC_PVDD11_S3_P1_IMON8 at (A 2) is labeled only once in the design.

Warnings in Page : @t6g_mb_lib.t6g(sch_1):Page225
Signal PVDD11_S3_P1_VCC1 at (B 4) is labeled only once in the design.
Signal SW_PVDD11_S3_P1_BOOT1_RC at (B 2) is labeled only once in the design.
Signal SW_PVDD11_S3_P1_BOOT1 at (B 3) is labeled only once in the design.
Signal SW_PVDD11_S3_P1_BOOT2_RC at (A 2) is labeled only once in the design.
Signal SW_PVDD11_S3_P1_BOOT2 at (A 3) is labeled only once in the design.
Signal SW_PVDD11_S3_P1_PH2 at (A 3) is labeled only once in the design.
Signal SW_PVDD11_S3_P1_SW1_RC at (B 3) is labeled only once in the design.
Signal PVDD11_S3_P1_LSET2 at (A 4) is labeled only once in the design.
Signal NC_PVDD11_S3_P1_DNC2 at (A 4) is labeled only once in the design.
Signal PVDD11_S3_P1_VCC2 at (A 4) is labeled only once in the design.
Signal SW_PVDD11_S3_P1_SW2 at (A 3) is labeled only once in the design.
Signal NC_PVDD11_S3_P1_GL1_2 at (A 3) is labeled only once in the design.
Signal NC_PVDD11_S3_P1_GL2_2 at (A 3) is labeled only once in the design.
Signal SW_PVDD11_S3_P1_SW2_RC at (A 3) is labeled only once in the design.
Signal PVDD11_S3_P1_LSET1 at (B 4) is labeled only once in the design.
Signal NC_PVDD11_S3_P1_DNC1 at (B 4) is labeled only once in the design.
Signal NC_PVDD11_S3_P1_GL2_1 at (B 3) is labeled only once in the design.
Signal NC_PVDD11_S3_P1_GL1_1 at (B 3) is labeled only once in the design.
Signal SW_PVDD11_S3_P1_SW1 at (B 3) is labeled only once in the design.
Signal PVDD11_S3_P1_VOS2 at (A 3) is labeled only once in the design.
Signal SW_PVDD11_S3_P1_PH1 at (B 3) is labeled only once in the design.
Signal PVDD11_S3_P1_VOS1 at (B 3) is labeled only once in the design.

Warnings in Page : @t6g_mb_lib.t6g(sch_1):Page226
Signal SW_PVDD18_S5_P1_SW at (B 3) is labeled only once in the design.
Signal PWRGD_PVDD18_S5_P1 at (B 3) is labeled only once in the design.
Signal PVDD18_S5_P1_FB_RC at (B 2) is labeled only once in the design.
Signal PVDD18_SS_P1_RGND at (B 3) is labeled only once in the design.
Signal PVDD18_S5_P1_REF at (B 3) is labeled only once in the design.
Signal PVDD18_S5_P1_MODE at (B 4) is labeled only once in the design.
Signal PVDD18_S5_P1_VCC at (B 4) is labeled only once in the design.
Signal PVDD18_S5_P1_CS at (B 4) is labeled only once in the design.
Signal SW_P12V_AUX_PVDD18_S5_P1_FLT at (B 4) is labeled only once in the design.
Signal PVDD18_S5_P1_FB at (B 3) is labeled only once in the design.
Signal SW_PVDD18_S5_P1_BST at (B 3) is labeled only once in the design.
Signal SW_PVDD18_S5_P1_BST_R at (B 3) is labeled only once in the design.

Warnings in Page : @t6g_mb_lib.t6g(sch_1):Page229
Signal DELTA_L_85_10INCH_IN3_DN at (B 2) is labeled only once in the design.
Signal DELTA_L_85_10INCH_IN3_DP at (B 2) is labeled only once in the design.
Signal DELTA_L_85_10INCH_BOT_DN at (B 2) is labeled only once in the design.
Signal DELTA_L_85_10INCH_BOT_DP at (B 2) is labeled only once in the design.
Signal DELTA_L_85_5INCH_TOP_DN at (B 4) is labeled only once in the design.
Signal DELTA_L_85_5INCH_IN5_DN at (A 4) is labeled only once in the design.
Signal DELTA_L_85_5INCH_IN5_DP at (A 4) is labeled only once in the design.
Signal DELTA_L_85_5INCH_IN4_DP at (A 4) is labeled only once in the design.
Signal DELTA_L_85_5INCH_IN4_DN at (A 4) is labeled only once in the design.
Signal DELTA_L_85_5INCH_TOP_DP at (B 4) is labeled only once in the design.
Signal DELTA_L_85_5INCH_BOT_DN at (B 4) is labeled only once in the design.
Signal DELTA_L_85_5INCH_BOT_DP at (B 4) is labeled only once in the design.
Signal DELTA_L_85_5INCH_IN1_DN at (B 4) is labeled only once in the design.
Signal DELTA_L_85_5INCH_IN1_DP at (B 4) is labeled only once in the design.
Signal DELTA_L_85_5INCH_IN2_DN at (B 4) is labeled only once in the design.
Signal DELTA_L_85_5INCH_IN2_DP at (B 4) is labeled only once in the design.
Signal DELTA_L_85_5INCH_IN6_DP at (A 4) is labeled only once in the design.
Signal DELTA_L_85_5INCH_IN6_DN at (A 4) is labeled only once in the design.
Signal DELTA_L_85_10INCH_TOP_DN at (B 2) is labeled only once in the design.
Signal DELTA_L_85_10INCH_TOP_DP at (B 2) is labeled only once in the design.
Signal DELTA_L_85_10INCH_IN1_DN at (B 2) is labeled only once in the design.
Signal DELTA_L_85_10INCH_IN1_DP at (B 2) is labeled only once in the design.
Signal DELTA_L_85_10INCH_IN2_DP at (B 2) is labeled only once in the design.
Signal DELTA_L_85_10INCH_IN2_DN at (B 2) is labeled only once in the design.
Signal DELTA_L_85_10INCH_IN6_DP at (A 2) is labeled only once in the design.
Signal DELTA_L_85_10INCH_IN6_DN at (A 2) is labeled only once in the design.
Signal DELTA_L_85_5INCH_IN3_DN at (B 4) is labeled only once in the design.
Signal DELTA_L_85_5INCH_IN3_DP at (B 4) is labeled only once in the design.
Signal DELTA_L_85_10INCH_IN4_DP at (A 2) is labeled only once in the design.
Signal DELTA_L_85_10INCH_IN5_DP at (A 2) is labeled only once in the design.
Signal DELTA_L_85_10INCH_IN5_DN at (A 2) is labeled only once in the design.
Signal DELTA_L_85_10INCH_IN4_DN at (A 2) is labeled only once in the design.

Warnings in Page : @t6g_mb_lib.t6g(sch_1):Page234
Signal CLK_GEN2_XTAL_IN at (B 3) is labeled only once in the design.
Signal CLK_GEN2_XTAL_OUT at (B 3) is labeled only once in the design.
Signal CLK_GEN2_BMC_RC_OE_R3_N at (B 3) is labeled only once in the design.
Signal CLK_100M_BMC_RC_DP_R at (B 2) is labeled only once in the design.
Signal CLK_100M_BMC_RC_DN_R at (B 2) is labeled only once in the design.
Signal CLK_100M_GPU_FPGA_DP_R at (B 2) is labeled only once in the design.
Signal CLK_100M_GPU_FPGA_DN_R at (B 2) is labeled only once in the design.
Signal CLK_GEN2_GPU_OE_N at (B 3) is labeled only once in the design.
Signal CLK_GEN2_XTAL_IN_R at (B 4) is labeled only once in the design.
Signal CLK_GEN2_GPU_FPGA_OE_R2_N at (A 4) is labeled only once in the design.
Signal GPU_FPGA_READY_R_N at (A 4) is labeled only once in the design.

Warnings in Page : @t6g_mb_lib.t6g(sch_1):Page235
Signal RST_USB_HUB_R_N at (B 4) is labeled only once in the design.
Signal    USB_HUB_RREF at (B 3) is labeled only once in the design.
Signal    USB_HUB_DVDD at (B 3) is labeled only once in the design.
Signal   USB_HUB_PGANG at (B 3) is labeled only once in the design.
Signal USB_HUB_XTAL_IN at (B 3) is labeled only once in the design.
Signal    USB_HUB_TEST at (B 3) is labeled only once in the design.
Signal  NC_USB_HUB_SDA at (B 2) is labeled only once in the design.
Signal USB_HUB_XTAL_OUT at (B 3) is labeled only once in the design.
Signal    USB2_P0_R_DP at (B 3) is labeled only once in the design.
Signal    TP_USB2_TEST at (A 4) is labeled only once in the design.
Signal   PD_U5201_VREG at (A 3) is labeled only once in the design.
Signal     PD_U5201_EQ at (A 3) is labeled only once in the design.
Signal USB2_HOST_BMC_B_BUF_DP at (A 3) is labeled only once in the design.
Signal USB2_HOST_BMC_B_BUF_DN at (A 3) is labeled only once in the design.
Signal   PD_U5201_RSTN at (A 3) is labeled only once in the design.
Signal      TP_USB2_CD at (A 4) is labeled only once in the design.
Signal  TP_USB2_ENA_HS at (A 2) is labeled only once in the design.
Signal P3V3_AUX_USB_HUB at (B 4) is labeled only once in the design.
Signal  NC_USB_HUB_DM4 at (B 2) is labeled only once in the design.
Signal    USB2_P0_R_DN at (B 3) is labeled only once in the design.
Signal  NC_USB_HUB_DM2 at (B 2) is labeled only once in the design.
Signal  NC_USB_HUB_DP2 at (B 2) is labeled only once in the design.
Signal  NC_USB_HUB_DP3 at (B 2) is labeled only once in the design.
Signal  NC_USB_HUB_DM3 at (B 2) is labeled only once in the design.
Signal  NC_USB_HUB_DP4 at (B 2) is labeled only once in the design.
Signal USB2_HUB_BUF_SWB_R_DP at (A 4) has too little display space.
Signal USB2_HUB_BUF_SWB_R_DN at (A 4) has too little display space.

Warnings in Page : @t6g_mb_lib.t6g(sch_1):Page236
Signal     U273_3_ADD1 at (A 3) is labeled only once in the design.
Signal     U273_3_ADD0 at (A 3) is labeled only once in the design.
Signal SMB_LM75_2_3V3AUX_SCL_R1 at (B 3) is labeled only once in the design.
Signal     U271_1_ADD2 at (B 2) is labeled only once in the design.
Signal     U270_0_ADD2 at (B 2) is labeled only once in the design.
Signal     U270_0_ADD1 at (B 2) is labeled only once in the design.
Signal     U270_0_ADD0 at (B 2) is labeled only once in the design.
Signal SMB_LM75_0_3V3AUX_SDA_R1 at (B 3) is labeled only once in the design.
Signal     U272_2_ADD2 at (A 2) is labeled only once in the design.
Signal     U273_3_ADD2 at (A 3) is labeled only once in the design.
Signal SMB_LM75_3_3V3AUX_SDA_R1 at (A 3) is labeled only once in the design.
Signal SMB_LM75_3_3V3AUX_SCL_R1 at (A 3) is labeled only once in the design.
Signal FM_LM75_3_ALERT_N at (A 3) is labeled only once in the design.
Signal SMB_LM75_2_3V3AUX_SDA_R1 at (B 3) is labeled only once in the design.
Signal FM_LM75_2_ALERT_N at (A 3) is labeled only once in the design.
Signal SMB_LM75_1_3V3AUX_SCL_R1 at (B 3) is labeled only once in the design.
Signal FM_G751_1_ALERT_N at (B 3) is labeled only once in the design.
Signal SMB_LM75_1_3V3AUX_SDA_R1 at (B 3) is labeled only once in the design.
Signal     U272_2_ADD0 at (B 2) is labeled only once in the design.
Signal     U272_2_ADD1 at (A 2) is labeled only once in the design.
Signal     U271_1_ADD0 at (B 2) is labeled only once in the design.
Signal     U271_1_ADD1 at (B 2) is labeled only once in the design.
Signal SMB_LM75_0_3V3AUX_SCL_R1 at (B 3) is labeled only once in the design.
Signal FM_G751_0_ALERT_N at (B 3) is labeled only once in the design.

Warnings in Page : @t6g_mb_lib.t6g(sch_1):Page237
Signal SMB_INA230_1_3V3AUX_SDA_R1 at (B 3) is labeled only once in the design.
Signal     INA230_1_A0 at (B 3) is labeled only once in the design.
Signal NC_INA230_2_NC3 at (A 2) is labeled only once in the design.
Signal VSENSE_P3V3_INA230_1_INP at (B 3) is labeled only once in the design.
Signal     INA230_2_A0 at (B 3) is labeled only once in the design.
Signal NC_INA230_2_NC2 at (A 2) is labeled only once in the design.
Signal NC_INA230_1_NC1 at (B 2) is labeled only once in the design.
Signal NC_INA230_1_NC0 at (B 2) is labeled only once in the design.
Signal     INA230_1_A1 at (B 3) is labeled only once in the design.
Signal VSENSE_P3V3_INA230_1_INN at (B 3) is labeled only once in the design.
Signal     INA230_2_A1 at (B 3) is labeled only once in the design.
Signal VSENSE_P3V3_INA230_2_INP at (A 3) is labeled only once in the design.
Signal VSENSE_P3V3_INA230_2_INN at (A 3) is labeled only once in the design.
Signal NC_INA230_2_NC0 at (A 2) is labeled only once in the design.
Signal SMB_INA230_2_3V3AUX_SCL_R1 at (A 3) is labeled only once in the design.
Signal SMB_INA230_2_3V3AUX_SDA_R1 at (A 3) is labeled only once in the design.
Signal SMB_INA230_1_3V3AUX_SCL_R1 at (B 3) is labeled only once in the design.
Signal NC_INA230_1_NC2 at (B 2) is labeled only once in the design.
Signal NC_INA230_1_NC3 at (B 2) is labeled only once in the design.
Signal NC_INA230_1_NC4 at (B 2) is labeled only once in the design.
Signal NC_INA230_1_NC5 at (B 2) is labeled only once in the design.
Signal OCP_SFF_P3V3_ADC_ALERT_R at (B 2) is labeled only once in the design.
Signal E1S_0_P3V3_ADC_ALERT_R at (A 2) is labeled only once in the design.
Signal NC_INA230_2_NC1 at (A 2) is labeled only once in the design.
Signal NC_INA230_2_NC4 at (A 2) is labeled only once in the design.
Signal NC_INA230_2_NC5 at (A 2) is labeled only once in the design.

Warnings in Page : @t6g_mb_lib.t6g(sch_1):Page238
Signal SMB_INA230_3_3V3AUX_SDA_R1 at (B 3) is labeled only once in the design.
Signal NC_INA230_4_NC5 at (B 2) is labeled only once in the design.
Signal     INA230_5_A0 at (A 3) is labeled only once in the design.
Signal NC_INA230_4_NC2 at (B 2) is labeled only once in the design.
Signal NC_INA230_4_NC4 at (B 2) is labeled only once in the design.
Signal     INA230_3_A1 at (B 3) is labeled only once in the design.
Signal     INA230_3_A0 at (B 3) is labeled only once in the design.
Signal VSENSE_P12V_INA230_5_INP at (A 3) is labeled only once in the design.
Signal VSENSE_P12V_INA230_5_INN at (A 3) is labeled only once in the design.
Signal NC_INA230_4_NC3 at (B 2) is labeled only once in the design.
Signal SMB_INA230_5_3V3AUX_SDA_R1 at (A 3) is labeled only once in the design.
Signal SMB_INA230_5_3V3AUX_SCL_R1 at (A 3) is labeled only once in the design.
Signal     INA230_4_A0 at (B 3) is labeled only once in the design.
Signal     INA230_4_A1 at (B 3) is labeled only once in the design.
Signal VSENSE_P12V_INA230_4_INN at (B 3) is labeled only once in the design.
Signal VSENSE_P12V_INA230_4_INP at (B 3) is labeled only once in the design.
Signal SMB_INA230_4_3V3AUX_SCL_R1 at (B 3) is labeled only once in the design.
Signal SMB_INA230_4_3V3AUX_SDA_R1 at (B 3) is labeled only once in the design.
Signal NC_INA230_4_NC1 at (B 2) is labeled only once in the design.
Signal NC_INA230_4_NC0 at (B 2) is labeled only once in the design.
Signal M2_0_P3V3_ADC_ALERT_R at (B 2) is labeled only once in the design.
Signal     INA230_5_A1 at (A 3) is labeled only once in the design.
Signal NC_INA230_5_NC0 at (A 2) is labeled only once in the design.
Signal NC_INA230_5_NC3 at (A 2) is labeled only once in the design.
Signal NC_INA230_5_NC4 at (A 2) is labeled only once in the design.
Signal NC_INA230_5_NC5 at (A 2) is labeled only once in the design.
Signal VSENSE_P12V_INA230_3_INP at (B 3) is labeled only once in the design.
Signal VSENSE_P12V_INA230_3_INN at (B 3) is labeled only once in the design.
Signal P12V_SCM_ADC_ALERT_R at (A 2) is labeled only once in the design.
Signal NC_INA230_5_NC1 at (A 2) is labeled only once in the design.
Signal NC_INA230_5_NC2 at (A 2) is labeled only once in the design.
Signal SMB_INA230_3_3V3AUX_SCL_R1 at (B 3) is labeled only once in the design.
Signal NC_INA230_3_NC5 at (B 2) is labeled only once in the design.
Signal NC_INA230_3_NC4 at (B 2) is labeled only once in the design.
Signal NC_INA230_3_NC3 at (B 2) is labeled only once in the design.
Signal NC_INA230_3_NC2 at (B 2) is labeled only once in the design.
Signal NC_INA230_3_NC1 at (B 2) is labeled only once in the design.
Signal NC_INA230_3_NC0 at (B 2) is labeled only once in the design.
Signal OCP_V3_2_P3V3_ADC_ALERT_R at (B 2) is labeled only once in the design.

Warnings in Page : @t6g_mb_lib.t6g(sch_1):Page239
Signal    PD_MB_FRU_WP at (B 3) is labeled only once in the design.
Signal SMB_FRU_3V3AUX_R1_SCL at (B 3) is labeled only once in the design.
Signal SMB_FRU_3V3AUX_R1_SDA at (B 3) is labeled only once in the design.
Signal   CPU_FRU_ADDR1 at (B 3) is labeled only once in the design.
Signal   CPU_FRU_ADDR2 at (B 3) is labeled only once in the design.
Signal    MB_FRU_ADDR1 at (B 3) is labeled only once in the design.
Signal   PD_CPU_FRU_WP at (B 3) is labeled only once in the design.
Signal   CPU_FRU_ADDR0 at (B 3) is labeled only once in the design.
Signal SMB_CPU_FRU_3V3AUX_SDA at (A 4) is labeled only once in the design.
Signal SMB_CPU_FRU_3V3AUX_SCL at (B 4) is labeled only once in the design.
Signal    MB_FRU_ADDR0 at (B 3) is labeled only once in the design.
Signal    MB_FRU_ADDR2 at (B 3) is labeled only once in the design.

Warnings in Page : @t6g_mb_lib.t6g(sch_1):Page241
Signal MB_PDB_SMB9_R_EN at (A 3) is labeled only once in the design.
Signal SMB_FAN_3V3AUX_R_SCL at (A 3) is labeled only once in the design.
Signal SMB_FAN_3V3AUX_R_SDA at (A 3) is labeled only once in the design.
Signal SMB_FAN_3V3AUX_BUF_SCL at (A 2) is labeled only once in the design.
Signal SMB_FAN_3V3AUX_BUF_SDA at (A 2) is labeled only once in the design.
Signal       TP_J45_A1 at (B 3) is labeled only once in the design.
Signal FM_PDB_BUF_EN_R1_N at (A 4) is labeled only once in the design.
Signal RST_SMB_SWITCH_R_N at (B 4) has too little display space.

Warnings in Page : @t6g_mb_lib.t6g(sch_1):Page242
Signal PWRGD_P3V3_AUX_PDB_R at (B 3) is labeled only once in the design.
Signal PWRGD_P3V3_AUX_PDB_BUF_R at (B 2) is labeled only once in the design.
Signal FM_GPU_HSC_EN_BUF_R at (B 2) is labeled only once in the design.
Signal     GPU_PRSNT_R at (B 3) is labeled only once in the design.
Signal HPDB_HSC_PWRGD_N at (A 3) is labeled only once in the design.

Warnings in Page : @t6g_mb_lib.t6g(sch_1):Page243
Signal FM_AC_PWR_BTN_PLD_N at (B 4) is labeled only once in the design.
Signal FM_AC_PWR_BTN_PLD_ISO_R_N at (B 3) is labeled only once in the design.
Signal FM_P12V_HSC_EN_R at (B 4) is labeled only once in the design.
Signal P12V_AUX_BLEEDING at (B 2) is labeled only once in the design.
Signal FM_P12V_HSC_EN_N at (B 3) is labeled only once in the design.
Signal FM_P12V_HSC_EN_R_N at (B 2) is labeled only once in the design.
Signal     NC_U8004_2Y at (B 3) is labeled only once in the design.

Warnings in Page : @t6g_mb_lib.t6g(sch_1):Page246
Signal PU_RST_SMB_U181_N at (B 3) is labeled only once in the design.
Signal     PU_U181_INT at (B 3) is labeled only once in the design.
Signal TP_TCA9539_0_P0_3 at (B 3) is labeled only once in the design.
Signal TP_TCA9539_0_P0_2 at (B 3) is labeled only once in the design.

Warnings in Page : @t6g_mb_lib.t6g(sch_1):Page248
Signal HP_LVC3_OCP_V3_1_R_EN at (B 3) is labeled only once in the design.
Signal HP_LVC3_OCP_V3_2_R_EN at (B 3) is labeled only once in the design.

Warnings in Page : @t6g_mb_lib.t6g(sch_1):Page249
Signal I3C_BMC_SWB_R_SDA at (A 3) is labeled only once in the design.
Signal SMB_BMC_SWB_EN_R2 at (A 3) is labeled only once in the design.
Signal SMB_2_BMC_GPU_R_SCL at (B 4) is labeled only once in the design.
Signal SMB_2_BMC_GPU_R_SDA at (B 4) is labeled only once in the design.
Signal SMB_BMC_GPU_EN_R3 at (B 4) is labeled only once in the design.
Signal SMB_2_BMC_GPU_BUF_R_SDA at (B 4) is labeled only once in the design.
Signal SMB_2_BMC_GPU_BUF_R_SCL at (B 4) is labeled only once in the design.
Signal SMB_BMC_SWB_EN_R at (B 4) is labeled only once in the design.
Signal SMB_BMC_SWB_R_SCL at (B 4) is labeled only once in the design.
Signal SMB_BMC_SWB_R_SDA at (B 4) is labeled only once in the design.
Signal I3C_BMC_SWB_BUF_R_SCL at (A 2) is labeled only once in the design.
Signal I3C_BMC_SWB_BUF_R_SDA at (A 2) is labeled only once in the design.
Signal SMB_1_BMC_GPU_BUF_R_SCL at (B 2) is labeled only once in the design.
Signal SMB_1_BMC_GPU_BUF_R_SDA at (B 2) is labeled only once in the design.
Signal SMB_1_BMC_GPU_R_SCL at (B 3) is labeled only once in the design.
Signal SMB_1_BMC_GPU_R_SDA at (B 3) is labeled only once in the design.
Signal SMB_BMC_GPU_EN_R1 at (B 3) is labeled only once in the design.
Signal SMB_BMC_SWB_BUF_R_SDA at (B 3) is labeled only once in the design.
Signal SMB_BMC_SWB_BUF_R_SCL at (B 3) is labeled only once in the design.
Signal I3C_BMC_SWB_R_SCL at (A 3) is labeled only once in the design.

Warnings in Page : @t6g_mb_lib.t6g(sch_1):Page251
Signal SMB_FRU_3V3AUX_SDA_R at (B 2) is labeled only once in the design.
Signal SMB_FRU_3V3AUX_SCL_R at (B 2) is labeled only once in the design.
Signal SMB_PCIE0_3V3AUX_SDA_R at (B 2) is labeled only once in the design.
Signal SMB_PCIE0_3V3AUX_SCL_R at (B 2) is labeled only once in the design.
Signal SMB_IOEXP_3V3AUX_SDA_R at (B 3) is labeled only once in the design.
Signal SMB_IOEXP_3V3AUX_SCL_R at (B 3) is labeled only once in the design.
Signal SMB_PCIE0_3V3AUX_SDA_R3 at (B 3) is labeled only once in the design.
Signal PU_RST_SMB_PCIE0_N at (B 3) is labeled only once in the design.
Signal SMB_USB_CPU0_HUB1_SDA_R at (B 3) is labeled only once in the design.
Signal SMB_USB_CPU0_HUB1_SCL_R at (B 3) is labeled only once in the design.
Signal SMB_PCIE0_3V3AUX_SCL_R3 at (B 3) is labeled only once in the design.
Signal SMB_PCIE0_3V3AUX_SDA_R5 at (B 3) is labeled only once in the design.
Signal SMB_PCIE0_3V3AUX_SCL_R5 at (B 3) is labeled only once in the design.
Signal SMB_INA230_3V3AUX_SDA_R at (B 2) is labeled only once in the design.
Signal SMB_INA230_3V3AUX_SCL_R at (B 2) is labeled only once in the design.
Signal SMB_BMC_SWB_SDA_R4 at (B 2) is labeled only once in the design.
Signal SMB_BMC_SWB_SCL_R4 at (B 2) is labeled only once in the design.

Warnings in Page : @t6g_mb_lib.t6g(sch_1):Page253
Signal     SMB_ADC_SDA at (B 2) is labeled only once in the design.
Signal SMB_LM75_3_3V3AUX_SDA_R at (B 2) is labeled only once in the design.
Signal SMB_P12V_HSC_SCL_R at (B 2) is labeled only once in the design.
Signal SMB_LM75_3_3V3AUX_SCL_R at (B 2) is labeled only once in the design.
Signal SMB_P12V_HSC_SDA_R at (B 2) is labeled only once in the design.
Signal PU_RST_SMB_PCIE2_N at (B 3) is labeled only once in the design.
Signal SMB_VR_3V3AUX_SDA_R6 at (B 3) is labeled only once in the design.
Signal SMB_LM75_2_3V3AUX_SDA_R at (B 3) is labeled only once in the design.
Signal SMB_VR_3V3AUX_SCL_R6 at (B 3) is labeled only once in the design.
Signal SMB_LM75_1_3V3AUX_SCL_R at (B 3) is labeled only once in the design.
Signal SMB_LM75_1_3V3AUX_SDA_R at (B 3) is labeled only once in the design.
Signal SMB_LM75_0_3V3AUX_SCL_R at (B 3) is labeled only once in the design.
Signal SMB_LM75_0_3V3AUX_SDA_R at (B 3) is labeled only once in the design.
Signal SMB_LM75_2_3V3AUX_SCL_R at (B 3) is labeled only once in the design.
Signal     SMB_ADC_SCL at (B 2) is labeled only once in the design.
Signal SMB_VR_SENSOR_3V3AUX_SCL_R at (B 2) is labeled only once in the design.
Signal SMB_VR_SENSOR_3V3AUX_SDA_R at (B 2) is labeled only once in the design.

Warnings in Page : @t6g_mb_lib.t6g(sch_1):Page254
Signal PWRGD_PS_PWROK_PLD_N at (B 3) is labeled only once in the design.
Signal PWRGD_PS_PWROK_PLD_ISO at (B 3) is labeled only once in the design.

Warnings in Page : @t6g_mb_lib.t6g(sch_1):Page255
Signal LED_PWRGD_P1V2_AUX_D at (B 2) is labeled only once in the design.
Signal LED_PWRGD_P1V2_AUX at (B 1) is labeled only once in the design.
Signal LED_PWRGD_P1V8_AUX at (B 4) is labeled only once in the design.
Signal LED_PWRGD_P1V8_AUX_D at (B 4) is labeled only once in the design.
Signal LED_PWRGD_SYS_PWROK_R at (A 4) is labeled only once in the design.
Signal         LED_P5V at (A 1) is labeled only once in the design.
Signal        LED_P3V3 at (A 1) is labeled only once in the design.
Signal LED_PWRGD_SYS_PWROK_R_D at (A 4) is labeled only once in the design.
Signal LED_RST_RSMRST_PLD_R_N_D at (B 4) is labeled only once in the design.
Signal LED_RST_RSMRST_PLD_R_N at (B 4) is labeled only once in the design.
Signal LED_PWRGD_PS_PWROK_PLD at (B 4) is labeled only once in the design.
Signal LED_PWRGD_PS_PWROK_PLD_D at (B 4) is labeled only once in the design.

Warnings in Page : @t6g_mb_lib.t6g(sch_1):Page256
Signal LED_PWRGD_PVDD33_S5_D at (B 4) is labeled only once in the design.
Signal LED_PWRGD_PVDDCR_SOC_P0_R at (B 4) is labeled only once in the design.
Signal LED_PWRGD_PVDD11_S3_P0_D at (B 2) is labeled only once in the design.
Signal LED_PWRGD_PVDD18_S5_P0_R at (B 1) is labeled only once in the design.
Signal LED_PWRGD_PVDD18_S5_P0_D at (B 2) is labeled only once in the design.
Signal LED_PWRGD_PVDDIO_P0_D at (B 2) is labeled only once in the design.
Signal LED_PWRGD_PVDD33_S5_R at (B 4) is labeled only once in the design.
Signal LED_PWRGD_PVDDCR_CPU0_P0_R at (B 4) is labeled only once in the design.
Signal LED_PWRGD_PVDDCR_CPU1_P0_D at (A 4) is labeled only once in the design.
Signal LED_PWRGD_PVDDCR_SOC_P0_D at (B 4) is labeled only once in the design.
Signal LED_PWRGD_PVDDIO_P0_R at (B 1) is labeled only once in the design.
Signal LED_PWRGD_PVDD11_S3_P0_R at (B 1) is labeled only once in the design.
Signal       NC_Q83_S2 at (A 2) is labeled only once in the design.
Signal       NC_Q83_G2 at (A 2) is labeled only once in the design.
Signal       NC_Q83_D2 at (A 2) is labeled only once in the design.
Signal LED_PWRGD_PVDDCR_CPU1_P0_R at (A 4) is labeled only once in the design.
Signal LED_PWRGD_PVDDCR_CPU0_P0_D at (B 4) is labeled only once in the design.

Warnings in Page : @t6g_mb_lib.t6g(sch_1):Page257
Signal LED_P12V_SCM_FAULT_D1 at (A 2) is labeled only once in the design.
Signal LED_P12V_SCM_FAULT at (A 1) is labeled only once in the design.
Signal LED_PWRGD_PVDDIO_P1_D at (A 4) is labeled only once in the design.
Signal LED_P12V_PSU_R1 at (A 2) is labeled only once in the design.
Signal LED_P12V_AUX_R2 at (B 2) is labeled only once in the design.
Signal LED_PWRGD_PVDD18_S5_P1_R at (B 1) is labeled only once in the design.
Signal LED_PWRGD_PVDDCR_SOC_P1_R at (B 4) is labeled only once in the design.
Signal LED_PWRGD_PVDD11_S3_P1_D at (B 2) is labeled only once in the design.
Signal LED_PWRGD_PVDD11_S3_P1_R at (B 1) is labeled only once in the design.
Signal LED_PWRGD_PVDDIO_P1_R at (A 4) is labeled only once in the design.
Signal LED_PWRGD_PVDDCR_CPU1_P1_R at (B 4) is labeled only once in the design.
Signal LED_PWRGD_PVDDCR_CPU1_P1_D at (B 4) is labeled only once in the design.
Signal LED_PWRGD_PVDDCR_SOC_P1_D at (B 4) is labeled only once in the design.
Signal LED_PWRGD_PVDDCR_CPU0_P1_R at (B 4) is labeled only once in the design.
Signal LED_PWRGD_PVDDCR_CPU0_P1_D at (B 4) is labeled only once in the design.
Signal LED_P12V_AUX_R3 at (B 1) is labeled only once in the design.
Signal LED_P12V_AUX_R1 at (B 2) is labeled only once in the design.
Signal LED_PWRGD_PVDD18_S5_P1_D at (B 2) is labeled only once in the design.
Signal LED_P12V_SCM_FAULT_D2 at (A 2) is labeled only once in the design.
Signal LED_P12V_PSU_R3 at (A 1) is labeled only once in the design.
Signal LED_P12V_PSU_R2 at (A 2) is labeled only once in the design.

Warnings in Page : @t6g_mb_lib.t6g(sch_1):Page258
Signal  P1V581_PDB_ADC at (A 4) is labeled only once in the design.
Signal   TP_ADC128_INT at (B 1) is labeled only once in the design.
Signal     ADC128_VREF at (A 2) is labeled only once in the design.
Signal P3V3_ADC128_VCC at (B 3) is labeled only once in the design.
Signal    P3V3_AUX_ADC at (B 4) is labeled only once in the design.
Signal        P3V3_ADC at (B 4) is labeled only once in the design.
Signal         P5V_ADC at (B 4) is labeled only once in the design.
Signal    P12V_AUX_ADC at (A 4) is labeled only once in the design.
Signal P3V3_MAX11617_VDD at (B 1) is labeled only once in the design.
Signal   MAX11617_VREF at (B 3) is labeled only once in the design.
Signal MAX11617_VREF_R at (B 2) is labeled only once in the design.

Warnings in Page : @t6g_mb_lib.t6g(sch_1):Page259
Signal PVDD18_S5_P0_ADC at (B 4) is labeled only once in the design.
Signal     P5V_AUX_ADC at (B 4) is labeled only once in the design.
Signal TP_ADC128_2_INT at (A 1) is labeled only once in the design.
Signal   ADC128_2_VREF at (A 2) is labeled only once in the design.
Signal PVDD18_S5_P1_ADC at (A 4) is labeled only once in the design.
Signal    P1V8_AUX_ADC at (B 4) is labeled only once in the design.
Signal    P1V2_AUX_ADC at (B 4) is labeled only once in the design.
Signal P1V8_CPU0_RT_1D_ADC at (A 4) is labeled only once in the design.
Signal P1V8_CPU1_RT_1D_ADC at (B 4) is labeled only once in the design.
Signal  PVDD_33_S5_ADC at (B 4) is labeled only once in the design.
Signal P3V3_ADC128_2_VCC at (B 3) is labeled only once in the design.
Signal P3V3_MAX11617_2_VDD at (B 1) is labeled only once in the design.
Signal MAX11617_2_VREF_R at (B 2) is labeled only once in the design.
Signal MAX11617_2_VREF at (B 3) is labeled only once in the design.

Warnings in Page : @t6g_mb_lib.t6g(sch_1):Page260
Signal PWRGD_P12V_MEM_CPU1_R at (A 3) is labeled only once in the design.
Signal        PU_U38_6 at (A 3) is labeled only once in the design.
Signal  PWRGD_P12V_MEM at (A 3) is labeled only once in the design.
Signal PWRGD_P12V_MEM_CPU0_EN at (B 4) is labeled only once in the design.
Signal PWRGD_P12V_MEM_CPU1_EN at (B 4) is labeled only once in the design.
Signal PWRGD_P12V_MEM_CPU0_EN_N at (B 3) is labeled only once in the design.
Signal PWRGD_P12V_MEM_CPU1_EN_N at (B 3) is labeled only once in the design.
Signal PWRGD_P12V_MEM_CPU0_R at (A 3) is labeled only once in the design.
Signal TP_P12V_AUX_CPU0_DIMM_ISEN_N at (B 4) is labeled only once in the design.
Signal TP_P12V_AUX_CPU1_DIMM_ISEN_N at (B 4) is labeled only once in the design.
Signal TP_P12V_AUX_CPU1_DIMM_ISEN_P at (B 4) is labeled only once in the design.
Signal TP_P12V_AUX_CPU0_DIMM_ISEN_P at (B 4) is labeled only once in the design.

Warnings in Page : @t6g_mb_lib.t6g(sch_1):Page261
Signal TDR_DIFF_85_TOP_DN at (B 1) is labeled only once in the design.
Signal TDR_DIFF_85_TOP_DP at (B 1) is labeled only once in the design.
Signal TDR_DIFF_85_IN1_DN at (B 1) is labeled only once in the design.
Signal TDR_DIFF_85_IN1_DP at (B 1) is labeled only once in the design.
Signal TDR_DIFF_85_IN2_DN at (B 1) is labeled only once in the design.
Signal TDR_DIFF_85_IN2_DP at (B 1) is labeled only once in the design.
Signal TDR_DIFF_85_IN4_DP at (B 1) is labeled only once in the design.
Signal TDR_DIFF_85_IN4_DN at (B 1) is labeled only once in the design.
Signal TDR_DIFF_85_IN5_DP at (A 1) is labeled only once in the design.
Signal TDR_DIFF_85_IN3_DN at (B 1) is labeled only once in the design.
Signal TDR_DIFF_85_IN3_DP at (B 1) is labeled only once in the design.
Signal TDR_DIFF_85_IN5_DN at (A 1) is labeled only once in the design.
Signal TDR_DIFF_85_IN6_DN at (A 1) is labeled only once in the design.
Signal TDR_DIFF_85_IN6_DP at (A 1) is labeled only once in the design.
Signal TDR_DIFF_85_BOT_DN at (A 1) is labeled only once in the design.
Signal TDR_DIFF_85_BOT_DP at (A 1) is labeled only once in the design.
Signal TDR_DIFF_80_TOP_DN at (B 3) is labeled only once in the design.
Signal TDR_DIFF_80_TOP_DP at (B 3) is labeled only once in the design.
Signal TDR_DIFF_80_IN1_DN at (B 3) is labeled only once in the design.
Signal TDR_DIFF_80_IN1_DP at (B 3) is labeled only once in the design.
Signal TDR_DIFF_80_IN2_DN at (B 3) is labeled only once in the design.
Signal TDR_DIFF_80_IN2_DP at (B 3) is labeled only once in the design.
Signal TDR_DIFF_80_IN3_DN at (B 3) is labeled only once in the design.
Signal TDR_DIFF_80_IN3_DP at (B 3) is labeled only once in the design.
Signal TDR_DIFF_80_IN4_DN at (B 3) is labeled only once in the design.
Signal TDR_DIFF_80_IN4_DP at (B 3) is labeled only once in the design.
Signal TDR_DIFF_80_IN5_DN at (A 3) is labeled only once in the design.
Signal TDR_DIFF_80_IN5_DP at (A 3) is labeled only once in the design.
Signal TDR_DIFF_80_IN6_DN at (A 3) is labeled only once in the design.
Signal TDR_DIFF_80_IN6_DP at (A 3) is labeled only once in the design.
Signal TDR_DIFF_80_BOT_DN at (A 3) is labeled only once in the design.
Signal TDR_DIFF_80_BOT_DP at (A 3) is labeled only once in the design.
Signal TDR_SE_50_OHM_TOP at (B 4) is labeled only once in the design.
Signal TDR_SE_50_OHM_IN2 at (B 4) is labeled only once in the design.
Signal TDR_SE_50_OHM_IN1 at (B 4) is labeled only once in the design.
Signal TDR_SE_50_OHM_IN3 at (B 4) is labeled only once in the design.
Signal TDR_SE_50_OHM_IN5 at (B 4) is labeled only once in the design.
Signal TDR_SE_50_OHM_BOT at (A 4) is labeled only once in the design.
Signal TDR_SE_50_OHM_IN4 at (B 4) is labeled only once in the design.
Signal TDR_SE_50_OHM_IN6 at (B 4) is labeled only once in the design.
Signal TDR_SE_45_OHM_IN4 at (B 4) is labeled only once in the design.
Signal TDR_SE_45_OHM_IN5 at (B 4) is labeled only once in the design.
Signal TDR_SE_45_OHM_BOT at (A 4) is labeled only once in the design.
Signal TDR_SE_45_OHM_IN6 at (B 4) is labeled only once in the design.
Signal TDR_SE_45_OHM_IN3 at (B 4) is labeled only once in the design.
Signal TDR_SE_45_OHM_IN1 at (B 4) is labeled only once in the design.
Signal TDR_SE_45_OHM_TOP at (B 4) is labeled only once in the design.
Signal TDR_SE_45_OHM_IN2 at (B 4) is labeled only once in the design.

Warnings in Page : @t6g_mb_lib.t6g(sch_1):Page262
Signal TDR_DIFF_85_NECK_IN6_DP at (A 3) is labeled only once in the design.
Signal TDR_DIFF_85_NECK_IN6_DN at (A 3) is labeled only once in the design.
Signal TDR_DIFF_85_NECK_IN5_DN at (A 3) is labeled only once in the design.
Signal TDR_DIFF_85_NECK_IN5_DP at (A 3) is labeled only once in the design.
Signal TDR_DIFF_85_NECK_IN4_DN at (B 3) is labeled only once in the design.
Signal TDR_DIFF_85_NECK_IN4_DP at (B 3) is labeled only once in the design.
Signal TDR_DIFF_85_NECK_IN3_DP at (B 3) is labeled only once in the design.
Signal TDR_DIFF_85_NECK_IN3_DN at (B 3) is labeled only once in the design.
Signal TDR_DIFF_85_NECK_IN2_DN at (B 3) is labeled only once in the design.
Signal TDR_DIFF_85_NECK_IN2_DP at (B 3) is labeled only once in the design.
Signal TDR_DIFF_85_NECK_IN1_DP at (B 3) is labeled only once in the design.
Signal TDR_DIFF_85_NECK_IN1_DN at (B 3) is labeled only once in the design.

Warnings in Page : @t6g_mb_lib.t6g(sch_1):Page263
Signal       HSC_VOSEN at (B 2) is labeled only once in the design.
Signal          HSC_CS at (B 2) is labeled only once in the design.
Signal      HSC_VSENSE at (B 3) is labeled only once in the design.
Signal        HSC_MODE at (B 2) is labeled only once in the design.
Signal        HSC_ON_R at (B 3) is labeled only once in the design.
Signal       HSC_VDD_R at (B 3) is labeled only once in the design.
Signal SMB_SML1_PMBUS_HSC_L_SCL at (B 4) is labeled only once in the design.
Signal SMB_SML1_PMBUS_HSC_R_SDA at (B 4) is labeled only once in the design.
Signal IRQ_SML1_PMBUS_ALERT at (B 3) is labeled only once in the design.
Signal        HSC_EN_R at (B 3) is labeled only once in the design.
Signal   HSC_VIN_UVW_N at (B 3) is labeled only once in the design.
Signal       HSC_VDD18 at (B 3) is labeled only once in the design.
Signal        HSC_ADDR at (B 3) is labeled only once in the design.

Warnings in Page : @t6g_mb_lib.t6g(sch_1):Page264
Signal  HSC_FLT_TYPE_2 at (A 3) is labeled only once in the design.
Signal       HSC_NC1_1 at (B 2) is labeled only once in the design.
Signal      HSC_MODE_1 at (B 3) is labeled only once in the design.
Signal     HSC_VDD_R_2 at (A 3) is labeled only once in the design.
Signal      HSC_MODE_2 at (A 3) is labeled only once in the design.
Signal       HSC_NC1_2 at (A 2) is labeled only once in the design.
Signal     HSC_VDD_R_1 at (B 3) is labeled only once in the design.
Signal     HSC_SCREF_1 at (B 3) is labeled only once in the design.
Signal        HSC_CS_1 at (B 3) is labeled only once in the design.
Signal  HSC_FLT_TYPE_1 at (B 3) is labeled only once in the design.
Signal      HSC_D_OC_1 at (B 3) is labeled only once in the design.
Signal     HSC_SCREF_2 at (A 3) is labeled only once in the design.
Signal        HSC_CS_2 at (A 3) is labeled only once in the design.
Signal      HSC_D_OC_2 at (A 3) is labeled only once in the design.

Warnings in Page : @t6g_mb_lib.t6g(sch_1):Page265
Signal      HSC_D_OC_4 at (A 3) is labeled only once in the design.
Signal  HSC_FLT_TYPE_4 at (A 3) is labeled only once in the design.
Signal       HSC_NC1_4 at (A 2) is labeled only once in the design.
Signal        HSC_CS_3 at (B 3) is labeled only once in the design.
Signal     HSC_VDD_R_4 at (A 3) is labeled only once in the design.
Signal     HSC_SCREF_4 at (A 3) is labeled only once in the design.
Signal      HSC_MODE_4 at (A 3) is labeled only once in the design.
Signal       HSC_NC1_3 at (B 2) is labeled only once in the design.
Signal     HSC_SCREF_3 at (B 3) is labeled only once in the design.
Signal      HSC_MODE_3 at (B 3) is labeled only once in the design.
Signal     HSC_VDD_R_3 at (B 3) is labeled only once in the design.
Signal  HSC_FLT_TYPE_3 at (B 3) is labeled only once in the design.
Signal      HSC_D_OC_3 at (B 3) is labeled only once in the design.
Signal        HSC_CS_4 at (A 3) is labeled only once in the design.

Warnings in Page : @t6g_mb_lib.t6g(sch_1):Page267
Signal  MB0_CM_GATE_G0 at (B 1) is labeled only once in the design.
Signal P12V_HSC_GATE_G1 at (A 4) is labeled only once in the design.
Signal P12V_HSC_GATE_G2 at (A 3) is labeled only once in the design.
Signal P12V_HSC_GATE_RC at (A 1) is labeled only once in the design.
Signal P12V_HSC_GATE_G6 at (A 2) is labeled only once in the design.
Signal P12V_HSC_GATE_G5 at (A 2) is labeled only once in the design.
Signal P12V_HSC_GATE_G4 at (A 3) is labeled only once in the design.
Signal P12V_HSC_GATE_G3 at (A 3) is labeled only once in the design.

Warnings in Page : @t6g_mb_lib.t6g(sch_1):Page268
Signal P12V_HSC_TEMP_D+ at (A 3) is labeled only once in the design.
Signal        P12V_AUX at (B 1) is labeled only once in the design.
Signal     HSC_D_OC_R2 at (B 4) is labeled only once in the design.
Signal         U142_VS at (B 4) is labeled only once in the design.
Signal P12V_HSC_T_CRIT_N at (A 3) is labeled only once in the design.
Signal A_HSC_LOW_DRAIN at (B 2) is labeled only once in the design.
Signal        P12V_PSU at (B 1) is labeled only once in the design.
Signal      A_HSC_HIGH at (B 4) is labeled only once in the design.
Signal       A_HSC_LOW at (B 4) is labeled only once in the design.
Signal      HSC_OC_VOL at (B 4) is labeled only once in the design.
Signal    OC_P2V5_COMP at (B 4) is labeled only once in the design.
Signal SMB_P12V_HSC_TEMP_SCL at (A 2) is labeled only once in the design.
Signal SMB_P12V_HSC_TEMP_SDA at (A 2) is labeled only once in the design.
Signal P12V_HSC_TEMP_ALERT_N at (A 2) is labeled only once in the design.
Signal P12V_HSC_TEMP_D- at (A 3) is labeled only once in the design.
Signal P12V_HSC_TEMP_E at (A 4) is labeled only once in the design.
Signal P12V_HSC_TEMP_R at (A 4) is labeled only once in the design.

Warnings in Page : @t6g_mb_lib.t6g(sch_1):Page269
Signal FM_UV_ADR_TRIGGER_N_R2 at (B 2) is labeled only once in the design.
Signal    UV_P2V5_COMP at (A 3) is labeled only once in the design.
Signal P12V_AUX_UV_ADR_TRIGGER at (B 3) is labeled only once in the design.
Signal UV_ADR_P2V5_COMP at (B 3) is labeled only once in the design.
Signal IRQ_UV_DETECT_R2_N at (A 2) is labeled only once in the design.
Signal A_P12V_STBY_FP_TRIGGER at (B 3) is labeled only once in the design.
Signal A_P12V_STBY_ADR_TRIGGER at (B 3) is labeled only once in the design.
Signal A_P12V_STBY_FPH_GATE at (B 2) is labeled only once in the design.
Signal P12V_AUX_UV_TRIGGER at (A 2) is labeled only once in the design.
Signal         U206_VS at (B 3) is labeled only once in the design.

Warnings in Page : @t6g_mb_lib.t6g(sch_1):Page270
Signal SW_P1V8_AUX_BT_R at (B 3) is labeled only once in the design.
Signal  SW_P1V8_AUX_PH at (B 3) is labeled only once in the design.
Signal  SW_P1V8_AUX_BT at (B 3) is labeled only once in the design.
Signal    P1V8_AUX_REF at (B 3) is labeled only once in the design.
Signal   P1V8_AUX_MODE at (B 4) is labeled only once in the design.
Signal     P1V8_AUX_FB at (B 3) is labeled only once in the design.
Signal     P1V8_AUX_CS at (A 4) is labeled only once in the design.
Signal    P1V8_AUX_VCC at (B 4) is labeled only once in the design.
Signal SW_P12V_AUX_P1V8_AUX_FLT at (B 4) is labeled only once in the design.
Signal P1V8_AUX_ENABLE at (B 4) is labeled only once in the design.
Signal  PWRGD_P1V8_AUX at (B 3) is labeled only once in the design.

Warnings in Page : @t6g_mb_lib.t6g(sch_1):Page271
Signal  SW_P1V2_AUX_PH at (B 3) is labeled only once in the design.
Signal  PWRGD_P1V2_AUX at (B 3) is labeled only once in the design.
Signal     P1V2_AUX_FB at (B 3) is labeled only once in the design.
Signal   P1V2_AUX_MODE at (B 4) is labeled only once in the design.
Signal     P1V2_AUX_CS at (A 4) is labeled only once in the design.
Signal SW_P12V_AUX_P1V2_AUX_FLT at (B 4) is labeled only once in the design.
Signal    P1V2_AUX_REF at (B 3) is labeled only once in the design.
Signal P1V2_AUX_ENABLE at (B 4) is labeled only once in the design.
Signal    P1V2_AUX_VCC at (B 4) is labeled only once in the design.
Signal  SW_P1V2_AUX_BT at (B 3) is labeled only once in the design.
Signal SW_P1V2_AUX_BT_R at (B 3) is labeled only once in the design.

Warnings in Page : @t6g_mb_lib.t6g(sch_1):Page272
Signal NC_HSC_TYPE_VINM at (B 3) is labeled only once in the design.
Signal HSC_TYPE_ADC_A1 at (B 3) is labeled only once in the design.
Signal SMB_HSC_TYPE_ADC_SCL at (B 3) is labeled only once in the design.
Signal NC_HSC_TYPE_NC5 at (B 2) is labeled only once in the design.
Signal NC_HSC_TYPE_NC4 at (B 2) is labeled only once in the design.
Signal NC_HSC_TYPE_NC3 at (B 2) is labeled only once in the design.
Signal NC_HSC_TYPE_NC2 at (B 2) is labeled only once in the design.
Signal NC_HSC_TYPE_NC1 at (B 2) is labeled only once in the design.
Signal NC_HSC_TYPE_NC0 at (B 2) is labeled only once in the design.
Signal HSC_TYPE_ADC_ALERT at (B 3) is labeled only once in the design.
Signal NC_HSC_TYPE_VINP at (B 3) is labeled only once in the design.
Signal SMB_HSC_TYPE_ADC_SDA at (B 3) is labeled only once in the design.
Signal HSC_TYPE_ADC_A0 at (B 3) is labeled only once in the design.

Warnings in Page : @t6g_mb_lib.t6g(sch_1):Page277
Signal CLKREQ_RT_CPU0_P0_N at (A 2) is labeled only once in the design.
Signal RST_RT_CPU0_P0_PERST_N at (A 2) is labeled only once in the design.
Signal SMB_RT_CPU0_P0_R2_SDA at (B 4) is labeled only once in the design.
Signal SMB_RT_CPU0_P0_R2_SCL at (B 4) is labeled only once in the design.
Signal CLK_100M_RETIMER_CPU0_P0_DP at (A 4) is labeled only once in the design.
Signal CLK_100M_RETIMER_CPU0_P0_DN at (A 4) is labeled only once in the design.
Signal JTAG_TRST_RT_CPU0_P0_N at (B 2) is labeled only once in the design.
Signal RST_RT_CPU0_P0_RESET_N at (A 2) is labeled only once in the design.
Signal SMB_RT_CPU0_P0_ROM_MUX_1D_R_SDA at (A 4) is labeled only once in the design.
Signal SMB_RT_CPU0_P0_ROM_MUX_1D_R_SCL at (A 4) is labeled only once in the design.

Warnings in Page : @t6g_mb_lib.t6g(sch_1):Page278
Signal NCF_CPU0_P0_GND at (A 1) is labeled only once in the design.
Signal NCF_A1_CPU0_P0_GND at (A 1) is labeled only once in the design.
Signal RT_CPU0_P0_VQPS at (B 4) is labeled only once in the design.

Warnings in Page : @t6g_mb_lib.t6g(sch_1):Page279
Signal          U11_E2 at (B 2) is labeled only once in the design.
Signal SMB_RT_CPU0_P0_ROM_SCL at (B 3) is labeled only once in the design.
Signal SMB_RT_CPU0_P0_ROM_SDA at (B 3) is labeled only once in the design.

Warnings in Page : @t6g_mb_lib.t6g(sch_1):Page288
Signal CLKREQ_RT_CPU0_P1_N at (A 2) is labeled only once in the design.
Signal JTAG_TRST_RT_CPU0_P1_N at (B 2) is labeled only once in the design.
Signal RST_RT_CPU0_P1_PERST_N at (A 2) is labeled only once in the design.
Signal CLK_100M_RETIMER_CPU0_P1_DP at (A 4) is labeled only once in the design.
Signal SMB_RT_CPU0_P1_R2_SCL at (B 4) is labeled only once in the design.
Signal CLK_100M_RETIMER_CPU0_P1_DN at (A 4) is labeled only once in the design.
Signal SMB_RT_CPU0_P1_R2_SDA at (B 4) is labeled only once in the design.
Signal RST_RT_CPU0_P1_RESET_N at (A 2) is labeled only once in the design.
Signal SMB_RT_CPU0_P1_ROM_MUX_1D_R_SDA at (A 4) is labeled only once in the design.
Signal SMB_RT_CPU0_P1_ROM_MUX_1D_R_SCL at (A 4) is labeled only once in the design.

Warnings in Page : @t6g_mb_lib.t6g(sch_1):Page289
Signal NCF_CPU0_P1_GND at (A 2) is labeled only once in the design.
Signal NCF_A1_CPU0_P1_GND at (A 2) is labeled only once in the design.
Signal RT_CPU0_P1_VQPS at (B 4) is labeled only once in the design.

Warnings in Page : @t6g_mb_lib.t6g(sch_1):Page290
Signal          U15_E2 at (B 2) is labeled only once in the design.
Signal SMB_RT_CPU0_P1_ROM_SCL at (B 3) is labeled only once in the design.
Signal SMB_RT_CPU0_P1_ROM_SDA at (B 3) is labeled only once in the design.

Warnings in Page : @t6g_mb_lib.t6g(sch_1):Page299
Signal SMB_RT_CPU0_P2_R2_SDA at (B 4) is labeled only once in the design.
Signal CLK_100M_RETIMER_CPU0_P2_DN at (A 4) is labeled only once in the design.
Signal CLK_100M_RETIMER_CPU0_P2_DP at (A 4) is labeled only once in the design.
Signal SMB_RT_CPU0_P2_R2_SCL at (B 4) is labeled only once in the design.
Signal JTAG_TRST_RT_CPU0_P2_N at (B 2) is labeled only once in the design.
Signal CLKREQ_RT_CPU0_P2_N at (A 2) is labeled only once in the design.
Signal RST_RT_CPU0_P2_PERST_N at (A 2) is labeled only once in the design.
Signal RST_RT_CPU0_P2_RESET_N at (A 2) is labeled only once in the design.
Signal SMB_RT_CPU0_P2_ROM_MUX_1D_R_SDA at (A 4) is labeled only once in the design.
Signal SMB_RT_CPU0_P2_ROM_MUX_1D_R_SCL at (A 4) is labeled only once in the design.

Warnings in Page : @t6g_mb_lib.t6g(sch_1):Page300
Signal NCF_CPU0_P2_GND at (A 1) is labeled only once in the design.
Signal NCF_A1_CPU0_P2_GND at (A 1) is labeled only once in the design.
Signal RT_CPU0_P2_VQPS at (B 4) is labeled only once in the design.

Warnings in Page : @t6g_mb_lib.t6g(sch_1):Page301
Signal          U16_E2 at (B 3) is labeled only once in the design.
Signal SMB_RT_CPU0_P2_ROM_SCL at (B 4) is labeled only once in the design.
Signal SMB_RT_CPU0_P2_ROM_SDA at (B 4) is labeled only once in the design.

Warnings in Page : @t6g_mb_lib.t6g(sch_1):Page310
Signal RST_RT_CPU0_P3_PERST_N at (A 2) is labeled only once in the design.
Signal JTAG_TRST_RT_CPU0_P3_N at (B 2) is labeled only once in the design.
Signal CLKREQ_RT_CPU0_P3_N at (A 2) is labeled only once in the design.
Signal SMB_RT_CPU0_P3_R2_SCL at (B 4) is labeled only once in the design.
Signal SMB_RT_CPU0_P3_R2_SDA at (B 4) is labeled only once in the design.
Signal CLK_100M_RETIMER_CPU0_P3_DN at (A 4) is labeled only once in the design.
Signal CLK_100M_RETIMER_CPU0_P3_DP at (A 4) is labeled only once in the design.
Signal RST_RT_CPU0_P3_RESET_N at (A 2) is labeled only once in the design.
Signal SMB_RT_CPU0_P3_ROM_MUX_1D_R_SDA at (A 4) is labeled only once in the design.
Signal SMB_RT_CPU0_P3_ROM_MUX_1D_R_SCL at (A 4) is labeled only once in the design.

Warnings in Page : @t6g_mb_lib.t6g(sch_1):Page311
Signal RT_CPU0_P3_VQPS at (B 4) is labeled only once in the design.
Signal NCF_CPU0_P3_GND at (A 1) is labeled only once in the design.
Signal NCF_A1_CPU0_P3_GND at (A 1) is labeled only once in the design.

Warnings in Page : @t6g_mb_lib.t6g(sch_1):Page312
Signal          U17_E2 at (B 3) is labeled only once in the design.
Signal SMB_RT_CPU0_P3_ROM_SCL at (B 4) is labeled only once in the design.
Signal SMB_RT_CPU0_P3_ROM_SDA at (B 4) is labeled only once in the design.

Warnings in Page : @t6g_mb_lib.t6g(sch_1):Page321
Signal SMB_RT_CPU1_P0_R2_SCL at (B 4) is labeled only once in the design.
Signal SMB_RT_CPU1_P0_R2_SDA at (B 4) is labeled only once in the design.
Signal CLK_100M_RETIMER_CPU1_P0_DN at (A 4) is labeled only once in the design.
Signal CLK_100M_RETIMER_CPU1_P0_DP at (A 4) is labeled only once in the design.
Signal JTAG_TRST_RT_CPU1_P0_N at (B 2) is labeled only once in the design.
Signal CLKREQ_RT_CPU1_P0_N at (A 2) is labeled only once in the design.
Signal RST_RT_CPU1_P0_PERST_N at (A 2) is labeled only once in the design.
Signal RST_RT_CPU1_P0_RESET_N at (A 2) is labeled only once in the design.
Signal SMB_RT_CPU1_P0_ROM_MUX_1D_R_SCL at (A 4) is labeled only once in the design.
Signal SMB_RT_CPU1_P0_ROM_MUX_1D_R_SDA at (A 4) is labeled only once in the design.

Warnings in Page : @t6g_mb_lib.t6g(sch_1):Page322
Signal NCF_A1_CPU1_P0_GND at (A 1) is labeled only once in the design.
Signal NCF_CPU1_P0_GND at (A 1) is labeled only once in the design.
Signal RT_CPU1_P0_VQPS at (B 4) is labeled only once in the design.

Warnings in Page : @t6g_mb_lib.t6g(sch_1):Page323
Signal          U12_E2 at (B 2) is labeled only once in the design.
Signal SMB_RT_CPU1_P0_ROM_SCL at (B 3) is labeled only once in the design.
Signal SMB_RT_CPU1_P0_ROM_SDA at (B 3) is labeled only once in the design.

Warnings in Page : @t6g_mb_lib.t6g(sch_1):Page332
Signal CLKREQ_RT_CPU1_P1_N at (A 2) is labeled only once in the design.
Signal RST_RT_CPU1_P1_PERST_N at (A 2) is labeled only once in the design.
Signal CLK_100M_RETIMER_CPU1_P1_DP at (A 3) is labeled only once in the design.
Signal CLK_100M_RETIMER_CPU1_P1_DN at (A 3) is labeled only once in the design.
Signal SMB_RT_CPU1_P1_R2_SCL at (B 3) is labeled only once in the design.
Signal SMB_RT_CPU1_P1_R2_SDA at (B 3) is labeled only once in the design.
Signal RST_RT_CPU1_P1_RESET_N at (A 2) is labeled only once in the design.
Signal JTAG_TRST_RT_CPU1_P1_N at (B 2) is labeled only once in the design.
Signal SMB_RT_CPU1_P1_ROM_MUX_1D_R_SDA at (A 4) is labeled only once in the design.
Signal SMB_RT_CPU1_P1_ROM_MUX_1D_R_SCL at (A 4) is labeled only once in the design.

Warnings in Page : @t6g_mb_lib.t6g(sch_1):Page333
Signal NCF_A1_CPU1_P1_GND at (A 1) is labeled only once in the design.
Signal NCF_CPU1_P1_GND at (A 1) is labeled only once in the design.
Signal RT_CPU1_P1_VQPS at (B 4) is labeled only once in the design.

Warnings in Page : @t6g_mb_lib.t6g(sch_1):Page334
Signal          U19_E2 at (B 2) is labeled only once in the design.
Signal SMB_RT_CPU1_P1_ROM_SCL at (B 3) is labeled only once in the design.
Signal SMB_RT_CPU1_P1_ROM_SDA at (B 3) is labeled only once in the design.

Warnings in Page : @t6g_mb_lib.t6g(sch_1):Page343
Signal RST_RT_CPU1_P2_RESET_N at (A 2) is labeled only once in the design.
Signal RST_RT_CPU1_P2_PERST_N at (A 2) is labeled only once in the design.
Signal CLKREQ_RT_CPU1_P2_N at (A 2) is labeled only once in the design.
Signal JTAG_TRST_RT_CPU1_P2_N at (B 2) is labeled only once in the design.
Signal SMB_RT_CPU1_P2_R2_SCL at (B 4) is labeled only once in the design.
Signal CLK_100M_RETIMER_CPU1_P2_DP at (A 4) is labeled only once in the design.
Signal CLK_100M_RETIMER_CPU1_P2_DN at (A 4) is labeled only once in the design.
Signal SMB_RT_CPU1_P2_R2_SDA at (B 4) is labeled only once in the design.
Signal SMB_RT_CPU1_P2_ROM_MUX_1D_R_SDA at (A 4) is labeled only once in the design.
Signal SMB_RT_CPU1_P2_ROM_MUX_1D_R_SCL at (A 4) is labeled only once in the design.

Warnings in Page : @t6g_mb_lib.t6g(sch_1):Page344
Signal NCF_A1_CPU1_P2_GND at (A 1) is labeled only once in the design.
Signal NCF_CPU1_P2_GND at (A 1) is labeled only once in the design.
Signal RT_CPU1_P2_VQPS at (B 4) is labeled only once in the design.

Warnings in Page : @t6g_mb_lib.t6g(sch_1):Page345
Signal          U20_E2 at (B 3) is labeled only once in the design.
Signal SMB_RT_CPU1_P2_ROM_SDA at (B 4) is labeled only once in the design.
Signal SMB_RT_CPU1_P2_ROM_SCL at (B 4) is labeled only once in the design.

Warnings in Page : @t6g_mb_lib.t6g(sch_1):Page354
Signal JTAG_TRST_RT_CPU1_P3_N at (B 2) is labeled only once in the design.
Signal RST_RT_CPU1_P3_RESET_N at (A 2) is labeled only once in the design.
Signal RST_RT_CPU1_P3_PERST_N at (A 2) is labeled only once in the design.
Signal SMB_RT_CPU1_P3_R2_SDA at (B 4) is labeled only once in the design.
Signal SMB_RT_CPU1_P3_R2_SCL at (B 4) is labeled only once in the design.
Signal CLK_100M_RETIMER_CPU1_P3_DP at (A 4) is labeled only once in the design.
Signal CLK_100M_RETIMER_CPU1_P3_DN at (A 4) is labeled only once in the design.
Signal CLKREQ_RT_CPU1_P3_N at (A 2) is labeled only once in the design.
Signal SMB_RT_CPU1_P3_ROM_MUX_1D_R_SDA at (A 4) is labeled only once in the design.
Signal SMB_RT_CPU1_P3_ROM_MUX_1D_R_SCL at (A 4) is labeled only once in the design.

Warnings in Page : @t6g_mb_lib.t6g(sch_1):Page355
Signal NCF_A1_CPU1_P3_GND at (A 1) is labeled only once in the design.
Signal NCF_CPU1_P3_GND at (A 1) is labeled only once in the design.
Signal RT_CPU1_P3_VQPS at (B 4) is labeled only once in the design.

Warnings in Page : @t6g_mb_lib.t6g(sch_1):Page356
Signal          U21_E2 at (B 2) is labeled only once in the design.
Signal SMB_RT_CPU1_P3_ROM_SCL at (B 3) is labeled only once in the design.
Signal SMB_RT_CPU1_P3_ROM_SDA at (B 3) is labeled only once in the design.

Warnings in Page : @t6g_mb_lib.t6g(sch_1):Page358
Signal NC_INA230_7_NC0 at (B 2) is labeled only once in the design.
Signal NC_INA230_7_NC2 at (B 2) is labeled only once in the design.
Signal NC_INA230_7_NC4 at (B 2) is labeled only once in the design.
Signal NC_INA230_7_NC5 at (B 2) is labeled only once in the design.
Signal NC_INA230_6_NC1 at (B 2) is labeled only once in the design.
Signal     INA230_8_A0 at (A 3) is labeled only once in the design.
Signal     INA230_8_A1 at (A 3) is labeled only once in the design.
Signal SMB_INA230_7_3V3AUX_SDA_R1 at (B 3) is labeled only once in the design.
Signal SMB_INA230_7_3V3AUX_SCL_R1 at (B 3) is labeled only once in the design.
Signal     INA230_7_A0 at (B 3) is labeled only once in the design.
Signal     INA230_7_A1 at (B 3) is labeled only once in the design.
Signal VSENSE_P12V_INA230_6_INN at (B 3) is labeled only once in the design.
Signal VSENSE_P12V_INA230_6_INP at (B 3) is labeled only once in the design.
Signal SMB_INA230_6_3V3AUX_SDA_R1 at (B 3) is labeled only once in the design.
Signal SMB_INA230_6_3V3AUX_SCL_R1 at (B 3) is labeled only once in the design.
Signal     INA230_6_A0 at (B 3) is labeled only once in the design.
Signal     INA230_6_A1 at (B 3) is labeled only once in the design.
Signal VSENSE_P12V_INA230_8_INN at (A 4) is labeled only once in the design.
Signal VSENSE_P12V_INA230_8_INP at (A 4) is labeled only once in the design.
Signal NC_INA230_6_NC0 at (B 2) is labeled only once in the design.
Signal VSENSE_P12V_INA230_7_INP at (B 3) is labeled only once in the design.
Signal VSENSE_P12V_INA230_7_INN at (B 3) is labeled only once in the design.
Signal NC_INA230_8_NC5 at (A 2) is labeled only once in the design.
Signal NC_INA230_6_NC4 at (B 2) is labeled only once in the design.
Signal NC_INA230_6_NC5 at (B 2) is labeled only once in the design.
Signal NC_INA230_6_NC3 at (B 2) is labeled only once in the design.
Signal NC_INA230_8_NC0 at (A 2) is labeled only once in the design.
Signal NC_INA230_8_NC4 at (A 2) is labeled only once in the design.
Signal NC_INA230_8_NC3 at (A 2) is labeled only once in the design.
Signal NC_INA230_8_NC2 at (A 2) is labeled only once in the design.
Signal NC_INA230_8_NC1 at (A 2) is labeled only once in the design.
Signal P12V_OCP_SFF_ADC_ALERT_R at (B 2) is labeled only once in the design.
Signal P12V_E1S_0_ADC_ALERT_R at (A 3) is labeled only once in the design.
Signal SMB_INA230_8_3V3AUX_SDA_R1 at (A 4) is labeled only once in the design.
Signal SMB_INA230_8_3V3AUX_SCL_R1 at (A 4) is labeled only once in the design.
Signal NC_INA230_7_NC3 at (B 2) is labeled only once in the design.
Signal NC_INA230_7_NC1 at (B 2) is labeled only once in the design.
Signal P12V_OCP_V3_2_ADC_ALERT_R at (B 2) is labeled only once in the design.
Signal NC_INA230_6_NC2 at (B 2) is labeled only once in the design.

Warnings in Page : @t6g_mb_lib.t6g(sch_1):Page361
Signal P1V8_RETIMER_CPU0_MODE at (B 4) is labeled only once in the design.
Signal PWRGD_P1V8_RETIMER_CPU0 at (B 3) is labeled only once in the design.
Signal P1V8_RETIMER_CPU0_FB at (B 3) is labeled only once in the design.
Signal P1V8_RETIMER_CPU0_VCC at (B 4) is labeled only once in the design.
Signal P1V8_RETIMER_CPU0_REF at (B 3) is labeled only once in the design.
Signal P1V8_RETIMER_CPU0_CS at (B 4) is labeled only once in the design.
Signal SW_P1V8_RETIMER_CPU0_BST_R at (B 3) is labeled only once in the design.
Signal SW_P1V8_RETIMER_CPU0_SW at (B 3) is labeled only once in the design.
Signal SW_P1V8_RETIMER_CPU0_BST at (B 3) is labeled only once in the design.
Signal SW_P12V_AUX_P1V8_RETIMER_CPU0_FLT at (B 4) is labeled only once in the design.

Warnings in Page : @t6g_mb_lib.t6g(sch_1):Page362
Signal SW_P1V8_RETIMER_CPU1_SW at (B 3) is labeled only once in the design.
Signal SW_P1V8_RETIMER_CPU1_BST_R at (B 3) is labeled only once in the design.
Signal P1V8_RETIMER_CPU1_CS at (B 4) is labeled only once in the design.
Signal P1V8_RETIMER_CPU1_VCC at (B 4) is labeled only once in the design.
Signal P1V8_RETIMER_CPU1_MODE at (B 4) is labeled only once in the design.
Signal P1V8_RETIMER_CPU1_REF at (B 3) is labeled only once in the design.
Signal SW_P1V8_RETIMER_CPU1_BST at (B 3) is labeled only once in the design.
Signal P1V8_RETIMER_CPU1_FB at (B 3) is labeled only once in the design.
Signal PWRGD_P1V8_RETIMER_CPU1 at (B 3) is labeled only once in the design.
Signal SW_P12V_AUX_P1V8_RETIMER_CPU1_FLT at (B 4) is labeled only once in the design.

Warnings in Page : @t6g_mb_lib.t6g(sch_1):Page363
Signal PWRGD_P0V9_RETIMER_CPU0_R at (B 4) is labeled only once in the design.
Signal P0V9_RETIMER_CPU0_SVID_SDA at (B 4) is labeled only once in the design.
Signal TP_P0V9_RETIMER_CPU0_SVID_ALERT_N at (B 4) is labeled only once in the design.
Signal TP_P0V9_RETIMER_CPU0_PMALERT at (B 3) is labeled only once in the design.
Signal P0V9_RETIMER_CPU0_PMSDA_R at (B 3) is labeled only once in the design.
Signal P0V9_RETIMER_CPU0_PMSCL_R at (B 3) is labeled only once in the design.
Signal P0V9_RETIMER_CPU0_CFP at (A 3) is labeled only once in the design.
Signal P0V9_RETIMER_CPU0_VRHOT at (A 2) is labeled only once in the design.
Signal NC_P0V9_RETIMER_CPU0_PWM7 at (B 2) is labeled only once in the design.
Signal NC_P0V9_RETIMER_CPU0_IMON8 at (A 2) is labeled only once in the design.
Signal NC_P0V9_RETIMER_CPU0_PWM3 at (B 2) is labeled only once in the design.
Signal NC_P0V9_RETIMER_CPU0_PWM4 at (B 2) is labeled only once in the design.
Signal P0V9_RETIMER_CPU0_ADDR at (A 3) is labeled only once in the design.
Signal P0V9_RETIMER_CPU0_VINSEN at (A 3) is labeled only once in the design.
Signal P0V9_RETIMER_CPU0_VMON at (A 3) is labeled only once in the design.
Signal NC_P0V9_RETIMER_CPU0_PG1 at (A 4) is labeled only once in the design.
Signal P0V9_RETIMER_CPU0_SENSE_R_P at (B 4) is labeled only once in the design.
Signal TP_P0V9_RETIMER_CPU0_VRHOT at (A 1) is labeled only once in the design.
Signal NC_P0V9_RETIMER_CPU0_PWM8 at (A 2) is labeled only once in the design.
Signal NC_P0V9_RETIMER_CPU0_PWM6 at (B 2) is labeled only once in the design.
Signal NC_P0V9_RETIMER_CPU0_PWM5 at (B 2) is labeled only once in the design.
Signal P0V9_RETIMER_CPU0_VCC at (B 2) is labeled only once in the design.
Signal NC_P0V9_RETIMER_CPU0_IMON3 at (B 2) is labeled only once in the design.
Signal NC_P0V9_RETIMER_CPU0_IMON4 at (B 2) is labeled only once in the design.
Signal NC_P0V9_RETIMER_CPU0_IMON5 at (B 2) is labeled only once in the design.
Signal NC_P0V9_RETIMER_CPU0_IMON6 at (B 2) is labeled only once in the design.
Signal NC_P0V9_RETIMER_CPU0_IMON7 at (A 2) is labeled only once in the design.
Signal P0V9_RETIMER_CPU0_TEMP1_R at (A 2) is labeled only once in the design.
Signal P0V9_RETIMER_CPU0_EN1_R at (A 3) is labeled only once in the design.
Signal P0V9_RETIMER_CPU0_INALERT at (A 3) is labeled only once in the design.
Signal P0V9_RETIMER_CPU0_EN0_R at (B 4) is labeled only once in the design.
Signal P0V9_RETIMER_CPU0_SVID_CLK at (B 4) is labeled only once in the design.
Signal P0V9_RETIMER_CPU0_SENSE_SH_P at (B 4) is labeled only once in the design.
Signal P0V9_RETIMER_CPU0_SENSE_SH_N at (B 4) is labeled only once in the design.

Warnings in Page : @t6g_mb_lib.t6g(sch_1):Page364
Signal P0V9_RETIMER_CPU0_VOS1 at (B 4) is labeled only once in the design.
Signal SW_P0V9_RETIMER_CPU0_SW2_RC at (A 3) is labeled only once in the design.
Signal NC_PV09_RETIMER_CPU0_DNC1 at (B 4) is labeled only once in the design.
Signal P0V9_RETIMER_CPU0_LSET1 at (B 4) is labeled only once in the design.
Signal SW_P0V9_RETIMER_CPU0_PH2 at (A 3) is labeled only once in the design.
Signal NC_PV09_RETIMER_CPU0_GL1_2 at (A 3) is labeled only once in the design.
Signal NC_PV09_RETIMER_CPU0_GL2_2 at (A 3) is labeled only once in the design.
Signal P0V9_RETIMER_CPU0_VOS2 at (A 3) is labeled only once in the design.
Signal SW_P0V9_RETIMER_CPU0_SW2 at (A 3) is labeled only once in the design.
Signal NC_PV09_RETIMER_CPU0_DNC2 at (A 4) is labeled only once in the design.
Signal P0V9_RETIMER_CPU0_LSET2 at (A 4) is labeled only once in the design.
Signal P0V9_RETIMER_CPU0_VCC2 at (A 4) is labeled only once in the design.
Signal SW_P0V9_RETIMER_CPU0_BOOT2 at (A 3) is labeled only once in the design.
Signal SW_P0V9_RETIMER_CPU0_BOOT2_RC at (A 3) is labeled only once in the design.
Signal SW_P0V9_RETIMER_CPU0_PH1 at (B 3) is labeled only once in the design.
Signal NC_PV09_RETIMER_CPU0_GL2_1 at (B 3) is labeled only once in the design.
Signal NC_PV09_RETIMER_CPU0_GL1_1 at (B 3) is labeled only once in the design.
Signal SW_P0V9_RETIMER_CPU0_SW1_RC at (B 3) is labeled only once in the design.
Signal SW_P0V9_RETIMER_CPU0_BOOT1_RC at (B 3) is labeled only once in the design.
Signal P0V9_RETIMER_CPU0_VCC1 at (B 4) is labeled only once in the design.
Signal SW_P0V9_RETIMER_CPU0_BOOT1 at (B 3) is labeled only once in the design.
Signal SW_P0V9_RETIMER_CPU0_SW1 at (B 3) is labeled only once in the design.

Warnings in Page : @t6g_mb_lib.t6g(sch_1):Page365
Signal PWRGD_P0V9_RETIMER_CPU1_R at (B 4) is labeled only once in the design.
Signal P0V9_RETIMER_CPU1_CFP at (A 3) is labeled only once in the design.
Signal P0V9_RETIMER_CPU1_SENSE_R_P at (B 4) is labeled only once in the design.
Signal NC_P0V9_RETIMER_CPU1_PG1 at (A 4) is labeled only once in the design.
Signal P0V9_RETIMER_CPU1_TEMP1_R at (A 2) is labeled only once in the design.
Signal NC_P0V9_RETIMER_CPU1_IMON8 at (A 2) is labeled only once in the design.
Signal NC_P0V9_RETIMER_CPU1_PWM8 at (A 2) is labeled only once in the design.
Signal NC_P0V9_RETIMER_CPU1_IMON7 at (A 2) is labeled only once in the design.
Signal NC_P0V9_RETIMER_CPU1_PWM7 at (B 2) is labeled only once in the design.
Signal NC_P0V9_RETIMER_CPU1_PWM6 at (B 2) is labeled only once in the design.
Signal NC_P0V9_RETIMER_CPU1_IMON5 at (B 2) is labeled only once in the design.
Signal NC_P0V9_RETIMER_CPU1_PWM5 at (B 2) is labeled only once in the design.
Signal NC_P0V9_RETIMER_CPU1_IMON4 at (B 2) is labeled only once in the design.
Signal NC_P0V9_RETIMER_CPU1_PWM4 at (B 2) is labeled only once in the design.
Signal NC_P0V9_RETIMER_CPU1_IMON3 at (B 2) is labeled only once in the design.
Signal NC_P0V9_RETIMER_CPU1_PWM3 at (B 2) is labeled only once in the design.
Signal P0V9_RETIMER_CPU1_VCC at (B 2) is labeled only once in the design.
Signal P0V9_RETIMER_CPU1_VINSEN at (A 4) is labeled only once in the design.
Signal P0V9_RETIMER_CPU1_ADDR at (A 3) is labeled only once in the design.
Signal NC_P0V9_RETIMER_CPU1_IMON6 at (B 2) is labeled only once in the design.
Signal TP_P0V9_RETIMER_CPU1_VRHOT at (A 1) is labeled only once in the design.
Signal P0V9_RETIMER_CPU1_VRHOT at (A 2) is labeled only once in the design.
Signal P0V9_RETIMER_CPU1_SVID_CLK at (B 4) is labeled only once in the design.
Signal P0V9_RETIMER_CPU1_SVID_SDA at (B 4) is labeled only once in the design.
Signal TP_P0V9_RETIMER_CPU1_SVID_ALERT_N at (B 4) is labeled only once in the design.
Signal TP_P0V9_RETIMER_CPU1_PMALERT at (B 4) is labeled only once in the design.
Signal P0V9_RETIMER_CPU1_PMSDA_R at (B 4) is labeled only once in the design.
Signal P0V9_RETIMER_CPU1_PMSCL_R at (B 4) is labeled only once in the design.
Signal P0V9_RETIMER_CPU1_VMON at (A 3) is labeled only once in the design.
Signal P0V9_RETIMER_CPU1_EN0_R at (B 4) is labeled only once in the design.
Signal P0V9_RETIMER_CPU1_INALERT at (A 4) is labeled only once in the design.
Signal P0V9_RETIMER_CPU1_EN1_R at (A 4) is labeled only once in the design.
Signal P0V9_RETIMER_CPU1_SENSE_SH_N at (B 4) is labeled only once in the design.
Signal P0V9_RETIMER_CPU1_SENSE_SH_P at (B 4) is labeled only once in the design.

Warnings in Page : @t6g_mb_lib.t6g(sch_1):Page366
Signal SW_P0V9_RETIMER_CPU1_BOOT1_RC at (B 3) is labeled only once in the design.
Signal SW_P0V9_RETIMER_CPU1_BOOT1 at (B 3) is labeled only once in the design.
Signal SW_P0V9_RETIMER_CPU1_BOOT2_RC at (A 3) is labeled only once in the design.
Signal SW_P0V9_RETIMER_CPU1_BOOT2 at (A 3) is labeled only once in the design.
Signal P0V9_RETIMER_CPU1_VOS1 at (B 4) is labeled only once in the design.
Signal SW_P0V9_RETIMER_CPU1_PH2 at (A 3) is labeled only once in the design.
Signal SW_P0V9_RETIMER_CPU1_SW2 at (A 3) is labeled only once in the design.
Signal P0V9_RETIMER_CPU1_VOS2 at (A 3) is labeled only once in the design.
Signal NC_PV09_RETIMER_CPU1_GL2_2 at (A 3) is labeled only once in the design.
Signal SW_P0V9_RETIMER_CPU1_PH1 at (B 3) is labeled only once in the design.
Signal SW_P0V9_RETIMER_CPU1_SW1 at (B 3) is labeled only once in the design.
Signal NC_PV09_RETIMER_CPU1_GL1_1 at (B 3) is labeled only once in the design.
Signal NC_PV09_RETIMER_CPU1_GL2_1 at (B 3) is labeled only once in the design.
Signal P0V9_RETIMER_CPU1_LSET1 at (B 4) is labeled only once in the design.
Signal SW_P0V9_RETIMER_CPU1_SW1_RC at (B 3) is labeled only once in the design.
Signal P0V9_RETIMER_CPU1_VCC1 at (B 4) is labeled only once in the design.
Signal P0V9_RETIMER_CPU1_VCC2 at (A 4) is labeled only once in the design.
Signal NC_PV09_RETIMER_CPU1_DNC2 at (A 4) is labeled only once in the design.
Signal P0V9_RETIMER_CPU1_LSET2 at (A 4) is labeled only once in the design.
Signal SW_P0V9_RETIMER_CPU1_SW2_RC at (A 3) is labeled only once in the design.
Signal NC_PV09_RETIMER_CPU1_GL1_2 at (A 3) is labeled only once in the design.
Signal NC_PV09_RETIMER_CPU1_DNC1 at (B 4) is labeled only once in the design.
